FILE_TYPE = MACRO_DRAWING;
SET COLOR_WIRE YELLOW;
SET COLOR_PROP ORANGE;
SET COLOR_DOT WHITE;
SET COLOR_ARC YELLOW;
SET COLOR_BODY GREEN;
SET COLOR_NOTE PURPLE;
SET PROP_DISPLAY VALUE;
SET PAGE_NUMBER P193;
FORCEADD UNIVERSAL_GND..1
(-8875 1100);
FORCEPROP 3 LASTPIN (-8875 1150) SIG_NAME GND\g
J 0
(-8865 1160);
DISPLAY 0.659574 (-8865 1160);
PAINT MONO (-8865 1160);
DISPLAY INVISIBLE (-8865 1160);
FORCEPROP 2 LAST CDS_LIB pure_quanta_power
J 0
(-8875 1100);
PAINT MONO (-8875 1100);
DISPLAY INVISIBLE (-8875 1100);
FORCEPROP 1 LAST PATH I1
J 0
(-8800 1100);
DISPLAY 0.872340 (-8800 1100);
PAINT AQUA (-8800 1100);
DISPLAY INVISIBLE (-8800 1100);
FORCEPROP 1 LAST HDL_POWER GND
J 1
(-8850 1025);
DISPLAY 0.872340 (-8850 1025);
PAINT GREEN (-8850 1025);
DISPLAY INVISIBLE (-8850 1025);
FORCEADD VCC_CORE..1
(-1025 4600);
FORCEPROP 3 LASTPIN (-1025 4550) SIG_NAME PVDDCR_CPU1_P1\g
J 0
(-1015 4560);
DISPLAY 0.659574 (-1015 4560);
PAINT MONO (-1015 4560);
DISPLAY INVISIBLE (-1015 4560);
FORCEPROP 1 LAST HDL_POWER PVDDCR_CPU1_P1
J 1
(-1025 4650);
DISPLAY 0.489362 (-1025 4650);
PAINT GREEN (-1025 4650);
FORCEPROP 2 LAST CDS_LIB pure_quanta_power
J 0
(-1025 4600);
DISPLAY INVISIBLE (-1025 4600);
FORCEPROP 1 LAST PATH I106
J 0
(-975 4625);
DISPLAY 0.872340 (-975 4625);
PAINT AQUA (-975 4625);
DISPLAY INVISIBLE (-975 4625);
FORCEADD UNIVERSAL_GND..1
(-1025 3875);
FORCEPROP 3 LASTPIN (-1025 3925) SIG_NAME GND\g
J 0
(-1015 3935);
DISPLAY 0.659574 (-1015 3935);
PAINT MONO (-1015 3935);
DISPLAY INVISIBLE (-1015 3935);
FORCEPROP 2 LAST CDS_LIB pure_quanta_power
J 0
(-1025 3875);
PAINT MONO (-1025 3875);
DISPLAY INVISIBLE (-1025 3875);
FORCEPROP 1 LAST PATH I107
J 0
(-950 3875);
DISPLAY 0.872340 (-950 3875);
PAINT AQUA (-950 3875);
DISPLAY INVISIBLE (-950 3875);
FORCEPROP 1 LAST HDL_POWER GND
J 1
(-1000 3800);
DISPLAY 0.872340 (-1000 3800);
PAINT GREEN (-1000 3800);
DISPLAY INVISIBLE (-1000 3800);
FORCEADD Q_CAP..1
(-1375 4250);
FORCEPROP 1 LAST LOCATION PC398_1
J 0
(-1325 4375);
DISPLAY 0.489362 (-1325 4375);
PAINT SKYBLUE (-1325 4375);
FORCEPROP 0 LAST $SEC 1
J 0
(-1325 4425);
DISPLAY 0.680851 (-1325 4425);
PAINT MONO (-1325 4425);
DISPLAY INVISIBLE (-1325 4425);
FORCEPROP 0 LAST CDS_SEC 1
J 0
(-1325 4425);
DISPLAY 1.021277 (-1325 4425);
DISPLAY INVISIBLE (-1325 4425);
FORCEPROP 1 LASTPIN (-1375 4350) $PN 1
J 0
(-1365 4330);
DISPLAY 0.489362 (-1365 4330);
PAINT MONO (-1365 4330);
FORCEPROP 1 LASTPIN (-1375 4150) $PN 2
J 0
(-1365 4130);
DISPLAY 0.489362 (-1365 4130);
PAINT MONO (-1365 4130);
FORCEPROP 1 LAST MATERIAL X6S
J 0
(-1325 4175);
DISPLAY 0.489362 (-1325 4175);
PAINT SKYBLUE (-1325 4175);
FORCEPROP 1 LAST TOLERANCE 20%
J 0
(-1325 4225);
DISPLAY 0.489362 (-1325 4225);
PAINT SKYBLUE (-1325 4225);
FORCEPROP 1 LAST VALUE 22UF
J 0
(-1325 4325);
DISPLAY 0.489362 (-1325 4325);
PAINT SKYBLUE (-1325 4325);
FORCEPROP 1 LAST VOLTAGE 4V
J 0
(-1325 4275);
DISPLAY 0.489362 (-1325 4275);
PAINT SKYBLUE (-1325 4275);
FORCEPROP 1 LAST PACK_TYPE 0805
J 0
(-1325 4125);
DISPLAY 0.489362 (-1325 4125);
PAINT SKYBLUE (-1325 4125);
FORCEPROP 2 LAST CDS_LIB pure_quanta
J 0
(-1375 4250);
DISPLAY INVISIBLE (-1375 4250);
FORCEPROP 1 LAST PATH I108
J 0
(-1325 4400);
DISPLAY 0.978723 (-1325 4400);
PAINT WHITE (-1325 4400);
DISPLAY INVISIBLE (-1325 4400);
FORCEPROP 1 LAST PART_NUMBER TMP_QCH622KMEA01
J 0
(-1325 4075);
DISPLAY 0.489362 (-1325 4075);
PAINT SKYBLUE (-1325 4075);
DISPLAY INVISIBLE (-1325 4075);
FORCEADD Q_CAP..1
(-1800 4250);
FORCEPROP 1 LAST LOCATION PC395_1
J 0
(-1750 4375);
DISPLAY 0.489362 (-1750 4375);
PAINT SKYBLUE (-1750 4375);
FORCEPROP 0 LAST $SEC 1
J 0
(-1750 4425);
DISPLAY 0.680851 (-1750 4425);
PAINT MONO (-1750 4425);
DISPLAY INVISIBLE (-1750 4425);
FORCEPROP 0 LAST CDS_SEC 1
J 0
(-1750 4425);
DISPLAY 1.021277 (-1750 4425);
DISPLAY INVISIBLE (-1750 4425);
FORCEPROP 1 LASTPIN (-1800 4350) $PN 1
J 0
(-1790 4330);
DISPLAY 0.489362 (-1790 4330);
PAINT MONO (-1790 4330);
FORCEPROP 1 LASTPIN (-1800 4150) $PN 2
J 0
(-1790 4130);
DISPLAY 0.489362 (-1790 4130);
PAINT MONO (-1790 4130);
FORCEPROP 1 LAST MATERIAL X6S
J 0
(-1750 4175);
DISPLAY 0.489362 (-1750 4175);
PAINT SKYBLUE (-1750 4175);
FORCEPROP 1 LAST TOLERANCE 20%
J 0
(-1750 4225);
DISPLAY 0.489362 (-1750 4225);
PAINT SKYBLUE (-1750 4225);
FORCEPROP 1 LAST VALUE 22UF
J 0
(-1750 4325);
DISPLAY 0.489362 (-1750 4325);
PAINT SKYBLUE (-1750 4325);
FORCEPROP 1 LAST PART_NUMBER TMP_QCH622KMEA01
J 0
(-1750 4075);
DISPLAY 0.489362 (-1750 4075);
PAINT SKYBLUE (-1750 4075);
FORCEPROP 1 LAST VOLTAGE 4V
J 0
(-1750 4275);
DISPLAY 0.489362 (-1750 4275);
PAINT SKYBLUE (-1750 4275);
FORCEPROP 1 LAST PACK_TYPE 0805
J 0
(-1750 4125);
DISPLAY 0.489362 (-1750 4125);
PAINT SKYBLUE (-1750 4125);
FORCEPROP 2 LAST CDS_LIB pure_quanta
J 0
(-1800 4250);
DISPLAY INVISIBLE (-1800 4250);
FORCEPROP 1 LAST PATH I109
J 0
(-1750 4400);
DISPLAY 0.978723 (-1750 4400);
PAINT WHITE (-1750 4400);
DISPLAY INVISIBLE (-1750 4400);
FORCEADD Q_CAP..1
(-2150 4250);
FORCEPROP 1 LAST LOCATION PC392
J 0
(-2100 4375);
DISPLAY 0.489362 (-2100 4375);
PAINT SKYBLUE (-2100 4375);
FORCEPROP 0 LAST $SEC 1
J 0
(-2100 4425);
DISPLAY 0.680851 (-2100 4425);
PAINT MONO (-2100 4425);
DISPLAY INVISIBLE (-2100 4425);
FORCEPROP 0 LAST CDS_SEC 1
J 0
(-2100 4425);
DISPLAY 1.021277 (-2100 4425);
DISPLAY INVISIBLE (-2100 4425);
FORCEPROP 1 LASTPIN (-2150 4350) $PN 1
J 0
(-2140 4330);
DISPLAY 0.489362 (-2140 4330);
PAINT MONO (-2140 4330);
FORCEPROP 1 LASTPIN (-2150 4150) $PN 2
J 0
(-2140 4130);
DISPLAY 0.489362 (-2140 4130);
PAINT MONO (-2140 4130);
FORCEPROP 1 LAST MATERIAL X7R
J 0
(-2100 4175);
DISPLAY 0.489362 (-2100 4175);
PAINT SKYBLUE (-2100 4175);
FORCEPROP 1 LAST TOLERANCE 10%
J 0
(-2100 4225);
DISPLAY 0.489362 (-2100 4225);
PAINT SKYBLUE (-2100 4225);
FORCEPROP 1 LAST VALUE 0.1UF
J 0
(-2100 4325);
DISPLAY 0.489362 (-2100 4325);
PAINT SKYBLUE (-2100 4325);
FORCEPROP 1 LAST PART_NUMBER CH4104K1B00
J 0
(-2100 4075);
DISPLAY 0.489362 (-2100 4075);
PAINT SKYBLUE (-2100 4075);
FORCEPROP 1 LAST VOLTAGE 25V
J 0
(-2100 4275);
DISPLAY 0.489362 (-2100 4275);
PAINT SKYBLUE (-2100 4275);
FORCEPROP 1 LAST PACK_TYPE 0402
J 0
(-2100 4125);
DISPLAY 0.489362 (-2100 4125);
PAINT SKYBLUE (-2100 4125);
FORCEPROP 2 LAST CDS_LIB pure_quanta
J 0
(-2150 4250);
DISPLAY INVISIBLE (-2150 4250);
FORCEPROP 1 LAST PATH I111
J 0
(-2100 4400);
DISPLAY 0.978723 (-2100 4400);
PAINT WHITE (-2100 4400);
DISPLAY INVISIBLE (-2100 4400);
FORCEADD Q_RES..1
(-3900 3425);
FORCEPROP 1 LAST LOCATION PR261
J 0
(-3950 3450);
DISPLAY 0.489362 (-3950 3450);
PAINT SKYBLUE (-3950 3450);
FORCEPROP 0 LAST $SEC 1
J 0
(-3650 3575);
DISPLAY 0.680851 (-3650 3575);
PAINT MONO (-3650 3575);
DISPLAY INVISIBLE (-3650 3575);
FORCEPROP 0 LAST CDS_SEC 1
J 0
(-3650 3575);
DISPLAY 1.021277 (-3650 3575);
DISPLAY INVISIBLE (-3650 3575);
FORCEPROP 1 LASTPIN (-4000 3425) $PN 1
J 0
(-3988 3437);
DISPLAY 0.489362 (-3988 3437);
PAINT MONO (-3988 3437);
FORCEPROP 1 LASTPIN (-3800 3425) $PN 2
J 0
(-3838 3437);
DISPLAY 0.489362 (-3838 3437);
PAINT MONO (-3838 3437);
FORCEPROP 1 LAST VALUE 0
J 2
(-4100 3450);
DISPLAY 0.489362 (-4100 3450);
PAINT SKYBLUE (-4100 3450);
FORCEPROP 1 LAST PART_NUMBER CS00002JB38
J 0
(-4200 3375);
DISPLAY 0.489362 (-4200 3375);
PAINT SKYBLUE (-4200 3375);
FORCEPROP 1 LAST WATTAGE 1/16W
J 2
(-3675 3475);
DISPLAY 0.489362 (-3675 3475);
PAINT SKYBLUE (-3675 3475);
FORCEPROP 1 LAST MATERIAL CHIP
J 0
(-3775 3325);
DISPLAY 0.489362 (-3775 3325);
PAINT SKYBLUE (-3775 3325);
FORCEPROP 1 LAST TOLERANCE 5%
J 0
(-4075 3450);
DISPLAY 0.489362 (-4075 3450);
PAINT SKYBLUE (-4075 3450);
FORCEPROP 1 LAST PACK_TYPE 0402LF
J 0
(-3800 3375);
DISPLAY 0.489362 (-3800 3375);
PAINT SKYBLUE (-3800 3375);
FORCEPROP 2 LAST CDS_LIB pure_quanta
J 0
(-3900 3425);
DISPLAY INVISIBLE (-3900 3425);
FORCEPROP 1 LAST PATH I112
J 0
(-3950 3575);
DISPLAY 0.978723 (-3950 3575);
PAINT WHITE (-3950 3575);
DISPLAY INVISIBLE (-3950 3575);
FORCEADD Q_RES..1
(-4625 600);
FORCEPROP 1 LAST LOCATION PR260
J 0
(-4675 625);
DISPLAY 0.489362 (-4675 625);
PAINT SKYBLUE (-4675 625);
FORCEPROP 0 LAST $SEC 1
J 0
(-4375 750);
DISPLAY 0.680851 (-4375 750);
PAINT MONO (-4375 750);
DISPLAY INVISIBLE (-4375 750);
FORCEPROP 0 LAST CDS_SEC 1
J 0
(-4375 750);
DISPLAY 1.021277 (-4375 750);
DISPLAY INVISIBLE (-4375 750);
FORCEPROP 1 LASTPIN (-4725 600) $PN 1
J 0
(-4713 612);
DISPLAY 0.489362 (-4713 612);
PAINT MONO (-4713 612);
FORCEPROP 1 LASTPIN (-4525 600) $PN 2
J 0
(-4563 612);
DISPLAY 0.489362 (-4563 612);
PAINT MONO (-4563 612);
FORCEPROP 1 LAST WATTAGE 1/16W
J 2
(-4400 675);
DISPLAY 0.489362 (-4400 675);
PAINT SKYBLUE (-4400 675);
FORCEPROP 1 LAST MATERIAL CHIP
J 0
(-4500 625);
DISPLAY 0.489362 (-4500 625);
PAINT SKYBLUE (-4500 625);
FORCEPROP 1 LAST TOLERANCE 5%
J 0
(-4800 625);
DISPLAY 0.489362 (-4800 625);
PAINT SKYBLUE (-4800 625);
FORCEPROP 1 LAST VALUE 0
J 2
(-4825 625);
DISPLAY 0.489362 (-4825 625);
PAINT SKYBLUE (-4825 625);
FORCEPROP 1 LAST PART_NUMBER CS00002JB38
J 0
(-4925 550);
DISPLAY 0.489362 (-4925 550);
PAINT SKYBLUE (-4925 550);
FORCEPROP 1 LAST PACK_TYPE 0402LF
J 0
(-4525 550);
DISPLAY 0.489362 (-4525 550);
PAINT SKYBLUE (-4525 550);
FORCEPROP 2 LAST CDS_LIB pure_quanta
J 0
(-4625 600);
DISPLAY INVISIBLE (-4625 600);
FORCEPROP 1 LAST PATH I124
J 0
(-4675 750);
DISPLAY 0.978723 (-4675 750);
PAINT WHITE (-4675 750);
DISPLAY INVISIBLE (-4675 750);
FORCEADD UNIVERSAL_GND..1
(-1350 1300);
FORCEPROP 3 LASTPIN (-1350 1350) SIG_NAME GND\g
J 0
(-1340 1360);
DISPLAY 0.659574 (-1340 1360);
PAINT MONO (-1340 1360);
DISPLAY INVISIBLE (-1340 1360);
FORCEPROP 2 LAST CDS_LIB pure_quanta_power
J 0
(-1350 1300);
PAINT MONO (-1350 1300);
DISPLAY INVISIBLE (-1350 1300);
FORCEPROP 1 LAST PATH I125
J 0
(-1275 1300);
DISPLAY 0.872340 (-1275 1300);
PAINT AQUA (-1275 1300);
DISPLAY INVISIBLE (-1275 1300);
FORCEPROP 1 LAST HDL_POWER GND
J 1
(-1325 1225);
DISPLAY 0.872340 (-1325 1225);
PAINT GREEN (-1325 1225);
DISPLAY INVISIBLE (-1325 1225);
FORCEADD VCC_CORE..1
(-1350 1925);
FORCEPROP 3 LASTPIN (-1350 1875) SIG_NAME PVDDCR_CPU1_P1\g
J 0
(-1340 1885);
DISPLAY 0.659574 (-1340 1885);
PAINT MONO (-1340 1885);
DISPLAY INVISIBLE (-1340 1885);
FORCEPROP 1 LAST HDL_POWER PVDDCR_CPU1_P1
J 1
(-1350 1975);
DISPLAY 0.489362 (-1350 1975);
PAINT GREEN (-1350 1975);
FORCEPROP 2 LAST CDS_LIB pure_quanta_power
J 0
(-1350 1925);
DISPLAY INVISIBLE (-1350 1925);
FORCEPROP 1 LAST PATH I126
J 0
(-1300 1950);
DISPLAY 0.872340 (-1300 1950);
PAINT AQUA (-1300 1950);
DISPLAY INVISIBLE (-1300 1950);
FORCEADD Q_CAP..1
(-1350 1625);
FORCEPROP 1 LAST LOCATION PC397_2
J 0
(-1300 1750);
DISPLAY 0.489362 (-1300 1750);
PAINT SKYBLUE (-1300 1750);
FORCEPROP 0 LAST $SEC 1
J 0
(-1300 1800);
DISPLAY 0.680851 (-1300 1800);
PAINT MONO (-1300 1800);
DISPLAY INVISIBLE (-1300 1800);
FORCEPROP 0 LAST CDS_SEC 1
J 0
(-1300 1800);
DISPLAY 1.021277 (-1300 1800);
DISPLAY INVISIBLE (-1300 1800);
FORCEPROP 1 LASTPIN (-1350 1725) $PN 1
J 0
(-1340 1705);
DISPLAY 0.489362 (-1340 1705);
PAINT MONO (-1340 1705);
FORCEPROP 1 LASTPIN (-1350 1525) $PN 2
J 0
(-1340 1505);
DISPLAY 0.489362 (-1340 1505);
PAINT MONO (-1340 1505);
FORCEPROP 1 LAST MATERIAL X6S
J 0
(-1300 1550);
DISPLAY 0.489362 (-1300 1550);
PAINT SKYBLUE (-1300 1550);
FORCEPROP 1 LAST TOLERANCE 20%
J 0
(-1300 1600);
DISPLAY 0.489362 (-1300 1600);
PAINT SKYBLUE (-1300 1600);
FORCEPROP 1 LAST VALUE 22UF
J 0
(-1300 1700);
DISPLAY 0.489362 (-1300 1700);
PAINT SKYBLUE (-1300 1700);
FORCEPROP 1 LAST PART_NUMBER TMP_QCH622KMEA01
J 0
(-1300 1450);
DISPLAY 0.489362 (-1300 1450);
PAINT SKYBLUE (-1300 1450);
FORCEPROP 1 LAST VOLTAGE 4V
J 0
(-1300 1650);
DISPLAY 0.489362 (-1300 1650);
PAINT SKYBLUE (-1300 1650);
FORCEPROP 1 LAST PACK_TYPE 0805
J 0
(-1300 1500);
DISPLAY 0.489362 (-1300 1500);
PAINT SKYBLUE (-1300 1500);
FORCEPROP 2 LAST CDS_LIB pure_quanta
J 0
(-1350 1625);
DISPLAY INVISIBLE (-1350 1625);
FORCEPROP 1 LAST PATH I127
J 0
(-1300 1775);
DISPLAY 0.978723 (-1300 1775);
PAINT WHITE (-1300 1775);
DISPLAY INVISIBLE (-1300 1775);
FORCEADD Q_CAP..1
(-1775 1625);
FORCEPROP 1 LAST LOCATION PC394_2
J 0
(-1725 1750);
DISPLAY 0.489362 (-1725 1750);
PAINT SKYBLUE (-1725 1750);
FORCEPROP 0 LAST $SEC 1
J 0
(-1725 1800);
DISPLAY 0.680851 (-1725 1800);
PAINT MONO (-1725 1800);
DISPLAY INVISIBLE (-1725 1800);
FORCEPROP 0 LAST CDS_SEC 1
J 0
(-1725 1800);
DISPLAY 1.021277 (-1725 1800);
DISPLAY INVISIBLE (-1725 1800);
FORCEPROP 1 LASTPIN (-1775 1725) $PN 1
J 0
(-1765 1705);
DISPLAY 0.489362 (-1765 1705);
PAINT MONO (-1765 1705);
FORCEPROP 1 LASTPIN (-1775 1525) $PN 2
J 0
(-1765 1505);
DISPLAY 0.489362 (-1765 1505);
PAINT MONO (-1765 1505);
FORCEPROP 1 LAST MATERIAL X6S
J 0
(-1725 1550);
DISPLAY 0.489362 (-1725 1550);
PAINT SKYBLUE (-1725 1550);
FORCEPROP 1 LAST TOLERANCE 20%
J 0
(-1725 1600);
DISPLAY 0.489362 (-1725 1600);
PAINT SKYBLUE (-1725 1600);
FORCEPROP 1 LAST VALUE 22UF
J 0
(-1725 1700);
DISPLAY 0.489362 (-1725 1700);
PAINT SKYBLUE (-1725 1700);
FORCEPROP 1 LAST PART_NUMBER TMP_QCH622KMEA01
J 0
(-1725 1450);
DISPLAY 0.489362 (-1725 1450);
PAINT SKYBLUE (-1725 1450);
FORCEPROP 1 LAST VOLTAGE 4V
J 0
(-1725 1650);
DISPLAY 0.489362 (-1725 1650);
PAINT SKYBLUE (-1725 1650);
FORCEPROP 1 LAST PACK_TYPE 0805
J 0
(-1725 1500);
DISPLAY 0.489362 (-1725 1500);
PAINT SKYBLUE (-1725 1500);
FORCEPROP 2 LAST CDS_LIB pure_quanta
J 0
(-1775 1625);
DISPLAY INVISIBLE (-1775 1625);
FORCEPROP 1 LAST PATH I128
J 0
(-1725 1775);
DISPLAY 0.978723 (-1725 1775);
PAINT WHITE (-1725 1775);
DISPLAY INVISIBLE (-1725 1775);
FORCEADD UNIVERSAL_GND..1
(-8850 3725);
FORCEPROP 3 LASTPIN (-8850 3775) SIG_NAME GND\g
J 0
(-8840 3785);
DISPLAY 0.659574 (-8840 3785);
PAINT MONO (-8840 3785);
DISPLAY INVISIBLE (-8840 3785);
FORCEPROP 2 LAST CDS_LIB pure_quanta_power
J 0
(-8850 3725);
PAINT MONO (-8850 3725);
DISPLAY INVISIBLE (-8850 3725);
FORCEPROP 1 LAST PATH I13
J 0
(-8775 3725);
DISPLAY 0.872340 (-8775 3725);
PAINT AQUA (-8775 3725);
DISPLAY INVISIBLE (-8775 3725);
FORCEPROP 1 LAST HDL_POWER GND
J 1
(-8825 3650);
DISPLAY 0.872340 (-8825 3650);
PAINT GREEN (-8825 3650);
DISPLAY INVISIBLE (-8825 3650);
FORCEADD Q_INDUCTOR4P_14..1
(-3175 1700);
FORCEPROP 1 LAST LOCATION PL41
J 0
(-3400 1955);
DISPLAY 0.489362 (-3400 1955);
PAINT SKYBLUE (-3400 1955);
FORCEPROP 0 LAST $SEC 1
J 0
(-3400 2000);
DISPLAY 0.680851 (-3400 2000);
PAINT MONO (-3400 2000);
DISPLAY INVISIBLE (-3400 2000);
FORCEPROP 0 LAST CDS_SEC 1
J 0
(-3400 2000);
DISPLAY 1.021277 (-3400 2000);
DISPLAY INVISIBLE (-3400 2000);
FORCEPROP 0 LASTPIN (-3575 1825) $PN 1
J 2
(-3585 1835);
DISPLAY 0.489362 (-3585 1835);
PAINT MONO (-3585 1835);
FORCEPROP 0 LASTPIN (-3575 1575) $PN 2
J 2
(-3585 1585);
DISPLAY 0.489362 (-3585 1585);
PAINT MONO (-3585 1585);
FORCEPROP 0 LASTPIN (-2775 1575) $PN 3
J 0
(-2765 1585);
DISPLAY 0.489362 (-2765 1585);
PAINT MONO (-2765 1585);
FORCEPROP 0 LASTPIN (-2775 1825) $PN 4
J 0
(-2765 1835);
DISPLAY 0.489362 (-2765 1835);
PAINT MONO (-2765 1835);
FORCEPROP 2 LAST PART_TYPE SMLF
J 0
(-3250 1450);
DISPLAY 1.021277 (-3250 1450);
FORCEPROP 1 LAST MATERIAL IND
J 0
(-3375 1875);
DISPLAY 0.489362 (-3375 1875);
PAINT SKYBLUE (-3375 1875);
FORCEPROP 1 LAST PART_NUMBER CV+15^0TZ04
J 0
(-3125 1875);
DISPLAY 0.489362 (-3125 1875);
PAINT SKYBLUE (-3125 1875);
FORCEPROP 2 LAST VALUE 150NH
J 0
(-3275 1875);
DISPLAY 0.489362 (-3275 1875);
PAINT SKYBLUE (-3275 1875);
FORCEPROP 1 LAST NEEDS_NO_SIZE TRUE
J 0
(-3175 1700);
DISPLAY 0.468085 (-3175 1700);
PAINT GREEN (-3175 1700);
DISPLAY INVISIBLE (-3175 1700);
FORCEPROP 2 LAST CDS_LIB pure_quanta
J 0
(-3175 1700);
DISPLAY INVISIBLE (-3175 1700);
FORCEPROP 1 LAST PATH I137
J 0
(-2975 1855);
DISPLAY 0.723404 (-2975 1855);
PAINT GREEN (-2975 1855);
DISPLAY INVISIBLE (-2975 1855);
FORCEADD Q_INDUCTOR4P_14..1
(-3575 4325);
FORCEPROP 1 LAST LOCATION PL40
J 0
(-3800 4580);
DISPLAY 0.489362 (-3800 4580);
PAINT SKYBLUE (-3800 4580);
FORCEPROP 0 LAST $SEC 1
J 0
(-3800 4625);
DISPLAY 0.680851 (-3800 4625);
PAINT MONO (-3800 4625);
DISPLAY INVISIBLE (-3800 4625);
FORCEPROP 0 LAST CDS_SEC 1
J 0
(-3800 4625);
DISPLAY 1.021277 (-3800 4625);
DISPLAY INVISIBLE (-3800 4625);
FORCEPROP 0 LASTPIN (-3975 4450) $PN 1
J 2
(-3985 4460);
DISPLAY 0.489362 (-3985 4460);
PAINT MONO (-3985 4460);
FORCEPROP 0 LASTPIN (-3975 4200) $PN 2
J 2
(-3985 4210);
DISPLAY 0.489362 (-3985 4210);
PAINT MONO (-3985 4210);
FORCEPROP 0 LASTPIN (-3175 4200) $PN 3
J 0
(-3165 4210);
DISPLAY 0.489362 (-3165 4210);
PAINT MONO (-3165 4210);
FORCEPROP 0 LASTPIN (-3175 4450) $PN 4
J 0
(-3165 4460);
DISPLAY 0.489362 (-3165 4460);
PAINT MONO (-3165 4460);
FORCEPROP 1 LAST MATERIAL IND
J 0
(-3775 4500);
DISPLAY 0.489362 (-3775 4500);
PAINT SKYBLUE (-3775 4500);
FORCEPROP 2 LAST PART_TYPE SMLF
J 0
(-3650 4075);
DISPLAY 1.021277 (-3650 4075);
FORCEPROP 2 LAST VALUE 150NH
J 0
(-3675 4500);
DISPLAY 0.489362 (-3675 4500);
PAINT SKYBLUE (-3675 4500);
FORCEPROP 1 LAST PART_NUMBER CV+15^0TZ04
J 0
(-3525 4500);
DISPLAY 0.489362 (-3525 4500);
PAINT SKYBLUE (-3525 4500);
FORCEPROP 2 LAST CDS_LIB pure_quanta
J 0
(-3575 4325);
DISPLAY INVISIBLE (-3575 4325);
FORCEPROP 1 LAST NEEDS_NO_SIZE TRUE
J 0
(-3575 4325);
DISPLAY 0.468085 (-3575 4325);
PAINT GREEN (-3575 4325);
DISPLAY INVISIBLE (-3575 4325);
FORCEPROP 1 LAST PATH I138
J 0
(-3375 4480);
DISPLAY 0.723404 (-3375 4480);
PAINT GREEN (-3375 4480);
DISPLAY INVISIBLE (-3375 4480);
FORCEADD Q_CAP..1
(-9375 1450);
FORCEPROP 1 LAST LOCATION PC373_2
J 0
(-9325 1550);
DISPLAY 0.489362 (-9325 1550);
PAINT SKYBLUE (-9325 1550);
FORCEPROP 0 LAST $SEC 1
J 0
(-9325 1575);
DISPLAY 0.680851 (-9325 1575);
PAINT MONO (-9325 1575);
DISPLAY INVISIBLE (-9325 1575);
FORCEPROP 0 LAST CDS_SEC 1
J 0
(-9125 1500);
DISPLAY 1.021277 (-9125 1500);
DISPLAY INVISIBLE (-9125 1500);
FORCEPROP 1 LASTPIN (-9375 1550) $PN 1
J 0
(-9365 1530);
DISPLAY 0.489362 (-9365 1530);
PAINT MONO (-9365 1530);
FORCEPROP 1 LASTPIN (-9375 1350) $PN 2
J 0
(-9365 1330);
DISPLAY 0.489362 (-9365 1330);
PAINT MONO (-9365 1330);
FORCEPROP 1 LAST MATERIAL X7R
J 0
(-9325 1350);
DISPLAY 0.489362 (-9325 1350);
PAINT SKYBLUE (-9325 1350);
FORCEPROP 1 LAST PART_NUMBER CH4104K1B00
J 0
(-9325 1300);
DISPLAY 0.489362 (-9325 1300);
PAINT SKYBLUE (-9325 1300);
FORCEPROP 1 LAST PACK_TYPE 0402
J 0
(-9325 1250);
DISPLAY 0.489362 (-9325 1250);
PAINT SKYBLUE (-9325 1250);
FORCEPROP 1 LAST VALUE 0.1UF
J 0
(-9325 1500);
DISPLAY 0.489362 (-9325 1500);
PAINT SKYBLUE (-9325 1500);
FORCEPROP 1 LAST VOLTAGE 25V
J 0
(-9325 1450);
DISPLAY 0.489362 (-9325 1450);
PAINT SKYBLUE (-9325 1450);
FORCEPROP 1 LAST TOLERANCE 10%
J 0
(-9325 1400);
DISPLAY 0.489362 (-9325 1400);
PAINT SKYBLUE (-9325 1400);
FORCEPROP 2 LAST CDS_LIB pure_quanta
J 0
(-9375 1450);
DISPLAY INVISIBLE (-9375 1450);
FORCEPROP 1 LAST PATH I139
J 0
(-9325 1600);
DISPLAY 0.978723 (-9325 1600);
PAINT WHITE (-9325 1600);
DISPLAY INVISIBLE (-9325 1600);
FORCEADD Q_RES..2
R 2
(-8850 3950);
FORCEPROP 1 LAST LOCATION PR255
J 2
(-8895 4075);
DISPLAY 0.489362 (-8895 4075);
PAINT SKYBLUE (-8895 4075);
FORCEPROP 0 LAST $SEC 1
J 0
(-8875 4125);
DISPLAY 0.680851 (-8875 4125);
PAINT MONO (-8875 4125);
DISPLAY INVISIBLE (-8875 4125);
FORCEPROP 0 LAST CDS_SEC 1
J 0
(-8875 4125);
DISPLAY 1.021277 (-8875 4125);
DISPLAY INVISIBLE (-8875 4125);
FORCEPROP 1 LASTPIN (-8850 4050) $PN 1
J 2
(-8855 4012);
DISPLAY 0.489362 (-8855 4012);
PAINT MONO (-8855 4012);
FORCEPROP 1 LASTPIN (-8850 3850) $PN 2
J 2
(-8855 3860);
DISPLAY 0.489362 (-8855 3860);
PAINT MONO (-8855 3860);
FORCEPROP 1 LAST WATTAGE 1/16W
J 2
(-8890 3925);
DISPLAY 0.489362 (-8890 3925);
PAINT SKYBLUE (-8890 3925);
FORCEPROP 1 LAST MATERIAL EMPTY
J 2
(-8890 3875);
DISPLAY 0.489362 (-8890 3875);
PAINT RED (-8890 3875);
FORCEPROP 1 LAST TOLERANCE 1%
J 2
(-8895 3975);
DISPLAY 0.489362 (-8895 3975);
PAINT SKYBLUE (-8895 3975);
FORCEPROP 1 LAST VALUE 8.87K
J 2
(-8895 4025);
DISPLAY 0.489362 (-8895 4025);
PAINT SKYBLUE (-8895 4025);
FORCEPROP 1 LAST PART_NUMBER CS28872FB01
J 2
(-8890 3825);
DISPLAY 0.489362 (-8890 3825);
PAINT SKYBLUE (-8890 3825);
FORCEPROP 1 LAST PACK_TYPE 0402LF
J 2
(-8890 3775);
DISPLAY 0.489362 (-8890 3775);
PAINT SKYBLUE (-8890 3775);
FORCEPROP 2 LAST CDS_LIB pure_quanta
J 2
(-8850 3950);
DISPLAY INVISIBLE (-8850 3950);
FORCEPROP 1 LAST PATH I14
J 2
(-8900 4125);
DISPLAY 0.978723 (-8900 4125);
PAINT WHITE (-8900 4125);
DISPLAY INVISIBLE (-8900 4125);
FORCEADD Q_CAP..1
(-9350 4075);
FORCEPROP 1 LAST LOCATION PC374_1
J 0
(-9300 4175);
DISPLAY 0.489362 (-9300 4175);
PAINT SKYBLUE (-9300 4175);
FORCEPROP 0 LAST $SEC 1
J 0
(-9300 4200);
DISPLAY 0.680851 (-9300 4200);
PAINT MONO (-9300 4200);
DISPLAY INVISIBLE (-9300 4200);
FORCEPROP 0 LAST CDS_SEC 1
J 0
(-9100 4125);
DISPLAY 1.021277 (-9100 4125);
DISPLAY INVISIBLE (-9100 4125);
FORCEPROP 1 LASTPIN (-9350 4175) $PN 1
J 0
(-9340 4155);
DISPLAY 0.489362 (-9340 4155);
PAINT MONO (-9340 4155);
FORCEPROP 1 LASTPIN (-9350 3975) $PN 2
J 0
(-9340 3955);
DISPLAY 0.489362 (-9340 3955);
PAINT MONO (-9340 3955);
FORCEPROP 1 LAST MATERIAL X7R
J 0
(-9300 3975);
DISPLAY 0.489362 (-9300 3975);
PAINT SKYBLUE (-9300 3975);
FORCEPROP 1 LAST TOLERANCE 10%
J 0
(-9300 4025);
DISPLAY 0.489362 (-9300 4025);
PAINT SKYBLUE (-9300 4025);
FORCEPROP 1 LAST VALUE 0.1UF
J 0
(-9300 4125);
DISPLAY 0.489362 (-9300 4125);
PAINT SKYBLUE (-9300 4125);
FORCEPROP 1 LAST PART_NUMBER CH4104K1B00
J 0
(-9300 3925);
DISPLAY 0.489362 (-9300 3925);
PAINT SKYBLUE (-9300 3925);
FORCEPROP 1 LAST VOLTAGE 25V
J 0
(-9300 4075);
DISPLAY 0.489362 (-9300 4075);
PAINT SKYBLUE (-9300 4075);
FORCEPROP 1 LAST PACK_TYPE 0402
J 0
(-9300 3875);
DISPLAY 0.489362 (-9300 3875);
PAINT SKYBLUE (-9300 3875);
FORCEPROP 2 LAST CDS_LIB pure_quanta
J 0
(-9350 4075);
DISPLAY INVISIBLE (-9350 4075);
FORCEPROP 1 LAST PATH I140
J 0
(-9300 4225);
DISPLAY 0.978723 (-9300 4225);
PAINT WHITE (-9300 4225);
DISPLAY INVISIBLE (-9300 4225);
FORCEADD Q_CAP..1
(-4600 4675);
FORCEPROP 1 LAST LOCATION PC383
J 0
(-4550 4775);
DISPLAY 0.489362 (-4550 4775);
PAINT SKYBLUE (-4550 4775);
FORCEPROP 0 LAST $SEC 1
J 0
(-4550 4825);
DISPLAY 0.680851 (-4550 4825);
PAINT MONO (-4550 4825);
DISPLAY INVISIBLE (-4550 4825);
FORCEPROP 0 LAST CDS_SEC 1
J 0
(-4550 4825);
DISPLAY 1.021277 (-4550 4825);
DISPLAY INVISIBLE (-4550 4825);
FORCEPROP 1 LASTPIN (-4600 4775) $PN 1
J 0
(-4590 4755);
DISPLAY 0.489362 (-4590 4755);
PAINT MONO (-4590 4755);
FORCEPROP 1 LASTPIN (-4600 4575) $PN 2
J 0
(-4590 4555);
DISPLAY 0.489362 (-4590 4555);
PAINT MONO (-4590 4555);
FORCEPROP 1 LAST VALUE 0.22UF
J 0
(-4550 4725);
DISPLAY 0.489362 (-4550 4725);
PAINT SKYBLUE (-4550 4725);
FORCEPROP 1 LAST PART_NUMBER CH4223K1B00
J 0
(-4550 4525);
DISPLAY 0.489362 (-4550 4525);
PAINT SKYBLUE (-4550 4525);
FORCEPROP 1 LAST VOLTAGE 16V
J 0
(-4550 4675);
DISPLAY 0.489362 (-4550 4675);
PAINT SKYBLUE (-4550 4675);
FORCEPROP 1 LAST PACK_TYPE 0402
J 0
(-4550 4475);
DISPLAY 0.489362 (-4550 4475);
PAINT SKYBLUE (-4550 4475);
FORCEPROP 1 LAST MATERIAL X7R
J 0
(-4550 4575);
DISPLAY 0.489362 (-4550 4575);
PAINT SKYBLUE (-4550 4575);
FORCEPROP 1 LAST TOLERANCE 10%
J 0
(-4550 4625);
DISPLAY 0.489362 (-4550 4625);
PAINT SKYBLUE (-4550 4625);
FORCEPROP 2 LAST CDS_LIB pure_quanta
J 2
(-4600 4675);
DISPLAY INVISIBLE (-4600 4675);
FORCEPROP 1 LAST PATH I141
J 0
(-4550 4825);
DISPLAY 0.978723 (-4550 4825);
PAINT WHITE (-4550 4825);
DISPLAY INVISIBLE (-4550 4825);
FORCEADD Q_RES..1
(-5675 4800);
FORCEPROP 1 LAST LOCATION PR258
J 0
(-5800 4925);
DISPLAY 0.489362 (-5800 4925);
PAINT SKYBLUE (-5800 4925);
FORCEPROP 0 LAST $SEC 1
J 0
(-5800 4950);
DISPLAY 0.680851 (-5800 4950);
PAINT MONO (-5800 4950);
DISPLAY INVISIBLE (-5800 4950);
FORCEPROP 0 LAST CDS_SEC 1
J 0
(-5800 4950);
DISPLAY 1.021277 (-5800 4950);
DISPLAY INVISIBLE (-5800 4950);
FORCEPROP 1 LASTPIN (-5775 4800) $PN 1
J 0
(-5763 4812);
DISPLAY 0.787234 (-5763 4812);
PAINT MONO (-5763 4812);
DISPLAY INVISIBLE (-5763 4812);
FORCEPROP 1 LASTPIN (-5575 4800) $PN 2
J 0
(-5613 4812);
DISPLAY 0.787234 (-5613 4812);
PAINT MONO (-5613 4812);
DISPLAY INVISIBLE (-5613 4812);
FORCEPROP 1 LAST PACK_TYPE 0402LF
J 0
(-5275 4725);
DISPLAY 0.489362 (-5275 4725);
PAINT SKYBLUE (-5275 4725);
FORCEPROP 1 LAST TOLERANCE 1%
J 0
(-5675 4875);
DISPLAY 0.489362 (-5675 4875);
PAINT SKYBLUE (-5675 4875);
FORCEPROP 1 LAST MATERIAL CHIP
J 0
(-5825 4725);
DISPLAY 0.489362 (-5825 4725);
PAINT SKYBLUE (-5825 4725);
FORCEPROP 1 LAST WATTAGE 1/16W
J 2
(-5400 4875);
DISPLAY 0.489362 (-5400 4875);
PAINT SKYBLUE (-5400 4875);
FORCEPROP 1 LAST VALUE 4.7
J 2
(-5725 4875);
DISPLAY 0.489362 (-5725 4875);
PAINT SKYBLUE (-5725 4875);
FORCEPROP 1 LAST PART_NUMBER CS-4702FB19
J 0
(-5650 4725);
DISPLAY 0.489362 (-5650 4725);
PAINT SKYBLUE (-5650 4725);
FORCEPROP 1 LAST PATH I142
J 0
(-5725 4950);
DISPLAY 0.978723 (-5725 4950);
PAINT WHITE (-5725 4950);
DISPLAY INVISIBLE (-5725 4950);
FORCEPROP 2 LAST CDS_LIB pure_quanta
J 0
(-5675 4800);
DISPLAY INVISIBLE (-5675 4800);
FORCEADD Q_CAP..1
(-4475 2050);
FORCEPROP 1 LAST LOCATION PC386
J 0
(-4425 2150);
DISPLAY 0.489362 (-4425 2150);
PAINT SKYBLUE (-4425 2150);
FORCEPROP 0 LAST $SEC 1
J 0
(-4425 2200);
DISPLAY 0.680851 (-4425 2200);
PAINT MONO (-4425 2200);
DISPLAY INVISIBLE (-4425 2200);
FORCEPROP 0 LAST CDS_SEC 1
J 2
(-4425 2175);
DISPLAY 1.021277 (-4425 2175);
DISPLAY INVISIBLE (-4425 2175);
FORCEPROP 1 LASTPIN (-4475 2150) $PN 1
J 0
(-4465 2130);
DISPLAY 0.489362 (-4465 2130);
PAINT MONO (-4465 2130);
FORCEPROP 1 LASTPIN (-4475 1950) $PN 2
J 0
(-4465 1930);
DISPLAY 0.489362 (-4465 1930);
PAINT MONO (-4465 1930);
FORCEPROP 1 LAST MATERIAL X7R
J 0
(-4425 1950);
DISPLAY 0.489362 (-4425 1950);
PAINT SKYBLUE (-4425 1950);
FORCEPROP 1 LAST TOLERANCE 10%
J 0
(-4425 2000);
DISPLAY 0.489362 (-4425 2000);
PAINT SKYBLUE (-4425 2000);
FORCEPROP 1 LAST VALUE 0.22UF
J 0
(-4425 2100);
DISPLAY 0.489362 (-4425 2100);
PAINT SKYBLUE (-4425 2100);
FORCEPROP 1 LAST PART_NUMBER CH4223K1B00
J 0
(-4425 1900);
DISPLAY 0.489362 (-4425 1900);
PAINT SKYBLUE (-4425 1900);
FORCEPROP 1 LAST VOLTAGE 16V
J 0
(-4425 2050);
DISPLAY 0.489362 (-4425 2050);
PAINT SKYBLUE (-4425 2050);
FORCEPROP 1 LAST PACK_TYPE 0402
J 0
(-4425 1850);
DISPLAY 0.489362 (-4425 1850);
PAINT SKYBLUE (-4425 1850);
FORCEPROP 2 LAST CDS_LIB pure_quanta
J 2
(-4475 2050);
DISPLAY INVISIBLE (-4475 2050);
FORCEPROP 1 LAST PATH I143
J 0
(-4425 2200);
DISPLAY 0.978723 (-4425 2200);
PAINT WHITE (-4425 2200);
DISPLAY INVISIBLE (-4425 2200);
FORCEADD Q_RES..1
(-5625 2175);
FORCEPROP 1 LAST LOCATION PR259
J 0
(-5850 2250);
DISPLAY 0.489362 (-5850 2250);
PAINT SKYBLUE (-5850 2250);
FORCEPROP 0 LAST $SEC 1
J 0
(-5350 2275);
DISPLAY 0.680851 (-5350 2275);
PAINT MONO (-5350 2275);
DISPLAY INVISIBLE (-5350 2275);
FORCEPROP 0 LAST CDS_SEC 1
J 0
(-5350 2275);
DISPLAY 1.021277 (-5350 2275);
DISPLAY INVISIBLE (-5350 2275);
FORCEPROP 1 LASTPIN (-5725 2175) $PN 1
J 0
(-5713 2187);
DISPLAY 0.787234 (-5713 2187);
PAINT MONO (-5713 2187);
DISPLAY INVISIBLE (-5713 2187);
FORCEPROP 1 LASTPIN (-5525 2175) $PN 2
J 0
(-5563 2187);
DISPLAY 0.787234 (-5563 2187);
PAINT MONO (-5563 2187);
DISPLAY INVISIBLE (-5563 2187);
FORCEPROP 1 LAST PACK_TYPE 0402LF
J 0
(-5225 2100);
DISPLAY 0.489362 (-5225 2100);
PAINT SKYBLUE (-5225 2100);
FORCEPROP 1 LAST MATERIAL CHIP
J 0
(-5775 2100);
DISPLAY 0.489362 (-5775 2100);
PAINT SKYBLUE (-5775 2100);
FORCEPROP 1 LAST TOLERANCE 1%
J 0
(-5625 2250);
DISPLAY 0.489362 (-5625 2250);
PAINT SKYBLUE (-5625 2250);
FORCEPROP 1 LAST WATTAGE 1/16W
J 2
(-5350 2250);
DISPLAY 0.489362 (-5350 2250);
PAINT SKYBLUE (-5350 2250);
FORCEPROP 1 LAST VALUE 4.7
J 2
(-5675 2250);
DISPLAY 0.489362 (-5675 2250);
PAINT SKYBLUE (-5675 2250);
FORCEPROP 1 LAST PART_NUMBER CS-4702FB19
J 0
(-5600 2100);
DISPLAY 0.489362 (-5600 2100);
PAINT SKYBLUE (-5600 2100);
FORCEPROP 1 LAST PATH I144
J 0
(-5675 2325);
DISPLAY 0.978723 (-5675 2325);
PAINT WHITE (-5675 2325);
DISPLAY INVISIBLE (-5675 2325);
FORCEPROP 2 LAST CDS_LIB pure_quanta
J 0
(-5625 2175);
DISPLAY INVISIBLE (-5625 2175);
FORCEADD OFFPAGE..5
(-8325 1825);
FORCEPROP 2 LAST $XR0 193 
J 0
(-8580 1825);
DISPLAY 0.638298 (-8580 1825);
PAINT MONO (-8580 1825);
FORCEPROP 1 LAST COMMENT_BODY TRUE
J 0
(-8225 1750);
DISPLAY 0.872340 (-8225 1750);
PAINT GREEN (-8225 1750);
DISPLAY INVISIBLE (-8225 1750);
FORCEPROP 2 LAST CDS_LIB standard
J 0
(-8325 1825);
DISPLAY INVISIBLE (-8325 1825);
FORCEPROP 2 LAST PATH I145
J 0
(-8275 1900);
DISPLAY 1.021277 (-8275 1900);
DISPLAY INVISIBLE (-8275 1900);
FORCEPROP 1 LAST OFFPAGE TRUE
J 0
(-8000 1700);
DISPLAY 0.872340 (-8000 1700);
PAINT GREEN (-8000 1700);
DISPLAY INVISIBLE (-8000 1700);
FORCEADD OFFPAGE..6
(-4225 1575);
FORCEPROP 2 LAST $XR0 194 
J 0
(-4535 1575);
DISPLAY 0.638298 (-4535 1575);
PAINT MONO (-4535 1575);
FORCEPROP 2 LAST PATH I146
J 0
(-4175 1650);
DISPLAY 1.021277 (-4175 1650);
DISPLAY INVISIBLE (-4175 1650);
FORCEPROP 1 LAST COMMENT_BODY TRUE
J 0
(-4125 1500);
DISPLAY 0.872340 (-4125 1500);
PAINT GREEN (-4125 1500);
DISPLAY INVISIBLE (-4125 1500);
FORCEPROP 2 LAST CDS_LIB standard
J 0
(-4225 1575);
DISPLAY INVISIBLE (-4225 1575);
FORCEPROP 1 LAST OFFPAGE TRUE
J 0
(-3900 1450);
DISPLAY 0.872340 (-3900 1450);
PAINT GREEN (-3900 1450);
DISPLAY INVISIBLE (-3900 1450);
FORCEADD OFFPAGE..6
R 2
(-2650 4200);
FORCEPROP 2 LAST $XR0 194 
J 0
(-2436 4200);
DISPLAY 0.638298 (-2436 4200);
PAINT MONO (-2436 4200);
FORCEPROP 1 LAST OFFPAGE TRUE
J 2
(-2975 4075);
DISPLAY 0.872340 (-2975 4075);
PAINT GREEN (-2975 4075);
DISPLAY INVISIBLE (-2975 4075);
FORCEPROP 2 LAST PATH I147
J 2
(-2700 4275);
DISPLAY 1.021277 (-2700 4275);
DISPLAY INVISIBLE (-2700 4275);
FORCEPROP 1 LAST COMMENT_BODY TRUE
J 2
(-2750 4125);
DISPLAY 0.872340 (-2750 4125);
PAINT GREEN (-2750 4125);
DISPLAY INVISIBLE (-2750 4125);
FORCEPROP 2 LAST CDS_LIB standard
J 2
(-2650 4200);
DISPLAY INVISIBLE (-2650 4200);
FORCEADD Q_CAPP..1
(-2575 2775);
FORCEPROP 1 LAST LOCATION PC387
J 0
(-2525 2875);
DISPLAY 0.489362 (-2525 2875);
PAINT SKYBLUE (-2525 2875);
FORCEPROP 0 LAST $SEC 1
J 0
(-2525 2925);
DISPLAY 0.680851 (-2525 2925);
PAINT MONO (-2525 2925);
DISPLAY INVISIBLE (-2525 2925);
FORCEPROP 0 LAST CDS_SEC 1
J 0
(-2525 2925);
DISPLAY 1.021277 (-2525 2925);
DISPLAY INVISIBLE (-2525 2925);
FORCEPROP 1 LASTPIN (-2575 2875) $PN 1
J 0
(-2565 2860);
DISPLAY 0.489362 (-2565 2860);
PAINT MONO (-2565 2860);
FORCEPROP 1 LASTPIN (-2575 2675) $PN 2
J 0
(-2565 2660);
DISPLAY 0.489362 (-2565 2660);
PAINT MONO (-2565 2660);
FORCEPROP 1 LAST PACK_TYPE SMLF
J 0
(-2525 2625);
DISPLAY 0.489362 (-2525 2625);
PAINT SKYBLUE (-2525 2625);
FORCEPROP 1 LAST VALUE 220UF
J 0
(-2525 2825);
DISPLAY 0.489362 (-2525 2825);
PAINT SKYBLUE (-2525 2825);
FORCEPROP 1 LAST TOLERANCE 20%
J 0
(-2525 2775);
DISPLAY 0.489362 (-2525 2775);
PAINT SKYBLUE (-2525 2775);
FORCEPROP 1 LAST MATERIAL SPCAP
J 0
(-2525 2675);
DISPLAY 0.489362 (-2525 2675);
PAINT SKYBLUE (-2525 2675);
FORCEPROP 1 LAST PART_NUMBER CH122KM8801
J 0
(-2525 2575);
DISPLAY 0.489362 (-2525 2575);
PAINT SKYBLUE (-2525 2575);
FORCEPROP 1 LAST VOLTAGE 4V
J 0
(-2525 2725);
DISPLAY 0.489362 (-2525 2725);
PAINT SKYBLUE (-2525 2725);
FORCEPROP 1 LAST PATH I148
J 0
(-2525 2925);
DISPLAY 0.978723 (-2525 2925);
DISPLAY INVISIBLE (-2525 2925);
FORCEPROP 2 LAST CDS_LIB pure_quanta
J 0
(-2575 2775);
DISPLAY INVISIBLE (-2575 2775);
FORCEADD UNIVERSAL_GND..1
(-1625 2400);
FORCEPROP 3 LASTPIN (-1625 2450) SIG_NAME GND\g
J 0
(-1615 2460);
DISPLAY 0.659574 (-1615 2460);
PAINT MONO (-1615 2460);
DISPLAY INVISIBLE (-1615 2460);
FORCEPROP 2 LAST CDS_LIB pure_quanta_power
J 0
(-1625 2400);
DISPLAY INVISIBLE (-1625 2400);
FORCEPROP 1 LAST PATH I149
J 0
(-1550 2400);
DISPLAY 0.872340 (-1550 2400);
PAINT AQUA (-1550 2400);
DISPLAY INVISIBLE (-1550 2400);
FORCEPROP 1 LAST HDL_POWER GND
J 1
(-1600 2325);
DISPLAY 0.872340 (-1600 2325);
PAINT GREEN (-1600 2325);
DISPLAY INVISIBLE (-1600 2325);
FORCEADD OFFPAGE..1
(-8275 3850);
FORCEPROP 2 LAST $XR0 193 
J 0
(-8527 3850);
DISPLAY 0.638298 (-8527 3850);
PAINT MONO (-8527 3850);
FORCEPROP 1 LAST COMMENT_BODY TRUE
J 0
(-8150 3750);
DISPLAY 0.872340 (-8150 3750);
PAINT GREEN (-8150 3750);
DISPLAY INVISIBLE (-8150 3750);
FORCEPROP 1 LAST OFFPAGE TRUE
J 0
(-7950 3725);
DISPLAY 0.872340 (-7950 3725);
PAINT GREEN (-7950 3725);
DISPLAY INVISIBLE (-7950 3725);
FORCEPROP 2 LAST CDS_LIB standard
J 0
(-8275 3850);
DISPLAY INVISIBLE (-8275 3850);
FORCEPROP 2 LAST PATH I15
J 0
(-8525 3900);
DISPLAY 1.021277 (-8525 3900);
DISPLAY INVISIBLE (-8525 3900);
FORCEADD Q_CAPP..1
(-2250 2775);
FORCEPROP 1 LAST LOCATION PC388
J 0
(-2200 2875);
DISPLAY 0.489362 (-2200 2875);
PAINT SKYBLUE (-2200 2875);
FORCEPROP 0 LAST $SEC 1
J 0
(-2200 2925);
DISPLAY 0.680851 (-2200 2925);
PAINT MONO (-2200 2925);
DISPLAY INVISIBLE (-2200 2925);
FORCEPROP 0 LAST CDS_SEC 1
J 0
(-2200 2925);
DISPLAY 1.021277 (-2200 2925);
DISPLAY INVISIBLE (-2200 2925);
FORCEPROP 1 LASTPIN (-2250 2875) $PN 1
J 0
(-2240 2860);
DISPLAY 0.489362 (-2240 2860);
PAINT MONO (-2240 2860);
FORCEPROP 1 LASTPIN (-2250 2675) $PN 2
J 0
(-2240 2660);
DISPLAY 0.489362 (-2240 2660);
PAINT MONO (-2240 2660);
FORCEPROP 1 LAST VALUE 220UF
J 0
(-2200 2825);
DISPLAY 0.489362 (-2200 2825);
PAINT SKYBLUE (-2200 2825);
FORCEPROP 1 LAST TOLERANCE 20%
J 0
(-2200 2775);
DISPLAY 0.489362 (-2200 2775);
PAINT SKYBLUE (-2200 2775);
FORCEPROP 1 LAST VOLTAGE 4V
J 0
(-2200 2725);
DISPLAY 0.489362 (-2200 2725);
PAINT SKYBLUE (-2200 2725);
FORCEPROP 1 LAST MATERIAL SPCAP
J 0
(-2200 2675);
DISPLAY 0.489362 (-2200 2675);
PAINT SKYBLUE (-2200 2675);
FORCEPROP 1 LAST PART_NUMBER CH122KM8801
J 0
(-2200 2575);
DISPLAY 0.489362 (-2200 2575);
PAINT SKYBLUE (-2200 2575);
FORCEPROP 1 LAST PACK_TYPE SMLF
J 0
(-2200 2625);
DISPLAY 0.489362 (-2200 2625);
PAINT SKYBLUE (-2200 2625);
FORCEPROP 1 LAST PATH I150
J 0
(-2200 2925);
DISPLAY 0.978723 (-2200 2925);
DISPLAY INVISIBLE (-2200 2925);
FORCEPROP 2 LAST CDS_LIB pure_quanta
J 0
(-2250 2775);
DISPLAY INVISIBLE (-2250 2775);
FORCEADD Q_CAPP..1
(-1925 2775);
FORCEPROP 1 LAST LOCATION PC389
J 0
(-1875 2875);
DISPLAY 0.489362 (-1875 2875);
PAINT SKYBLUE (-1875 2875);
FORCEPROP 0 LAST $SEC 1
J 0
(-1875 2925);
DISPLAY 0.680851 (-1875 2925);
PAINT MONO (-1875 2925);
DISPLAY INVISIBLE (-1875 2925);
FORCEPROP 0 LAST CDS_SEC 1
J 0
(-1875 2925);
DISPLAY 1.021277 (-1875 2925);
DISPLAY INVISIBLE (-1875 2925);
FORCEPROP 1 LASTPIN (-1925 2875) $PN 1
J 0
(-1915 2860);
DISPLAY 0.489362 (-1915 2860);
PAINT MONO (-1915 2860);
FORCEPROP 1 LASTPIN (-1925 2675) $PN 2
J 0
(-1915 2660);
DISPLAY 0.489362 (-1915 2660);
PAINT MONO (-1915 2660);
FORCEPROP 1 LAST PACK_TYPE SMLF
J 0
(-1875 2625);
DISPLAY 0.489362 (-1875 2625);
PAINT SKYBLUE (-1875 2625);
FORCEPROP 1 LAST VOLTAGE 4V
J 0
(-1875 2725);
DISPLAY 0.489362 (-1875 2725);
PAINT SKYBLUE (-1875 2725);
FORCEPROP 1 LAST VALUE 220UF
J 0
(-1875 2825);
DISPLAY 0.489362 (-1875 2825);
PAINT SKYBLUE (-1875 2825);
FORCEPROP 1 LAST TOLERANCE 20%
J 0
(-1875 2775);
DISPLAY 0.489362 (-1875 2775);
PAINT SKYBLUE (-1875 2775);
FORCEPROP 1 LAST MATERIAL SPCAP
J 0
(-1875 2675);
DISPLAY 0.489362 (-1875 2675);
PAINT SKYBLUE (-1875 2675);
FORCEPROP 1 LAST PART_NUMBER CH122KM8801
J 0
(-1875 2575);
DISPLAY 0.489362 (-1875 2575);
PAINT SKYBLUE (-1875 2575);
FORCEPROP 1 LAST PATH I151
J 0
(-1875 2925);
DISPLAY 0.978723 (-1875 2925);
DISPLAY INVISIBLE (-1875 2925);
FORCEPROP 2 LAST CDS_LIB pure_quanta
J 0
(-1925 2775);
DISPLAY INVISIBLE (-1925 2775);
FORCEADD VCC_CORE..1
(-1625 3075);
FORCEPROP 3 LASTPIN (-1625 3025) SIG_NAME PVDDCR_CPU1_P1\g
J 0
(-1615 3035);
DISPLAY 0.659574 (-1615 3035);
PAINT MONO (-1615 3035);
DISPLAY INVISIBLE (-1615 3035);
FORCEPROP 1 LAST HDL_POWER PVDDCR_CPU1_P1
J 1
(-1625 3125);
DISPLAY 0.489362 (-1625 3125);
PAINT GREEN (-1625 3125);
FORCEPROP 2 LAST CDS_LIB pure_quanta_power
J 0
(-1625 3075);
DISPLAY INVISIBLE (-1625 3075);
FORCEPROP 1 LAST PATH I152
J 0
(-1575 3100);
DISPLAY 0.872340 (-1575 3100);
PAINT AQUA (-1575 3100);
DISPLAY INVISIBLE (-1575 3100);
FORCEADD Q_CAPP..1
(-1625 2775);
FORCEPROP 1 LAST LOCATION PC391
J 0
(-1575 2875);
DISPLAY 0.489362 (-1575 2875);
PAINT SKYBLUE (-1575 2875);
FORCEPROP 0 LAST $SEC 1
J 0
(-1575 2925);
DISPLAY 0.680851 (-1575 2925);
PAINT MONO (-1575 2925);
DISPLAY INVISIBLE (-1575 2925);
FORCEPROP 0 LAST CDS_SEC 1
J 0
(-1575 2925);
DISPLAY 1.021277 (-1575 2925);
DISPLAY INVISIBLE (-1575 2925);
FORCEPROP 1 LASTPIN (-1625 2875) $PN 1
J 0
(-1615 2860);
DISPLAY 0.489362 (-1615 2860);
PAINT MONO (-1615 2860);
FORCEPROP 1 LASTPIN (-1625 2675) $PN 2
J 0
(-1615 2660);
DISPLAY 0.489362 (-1615 2660);
PAINT MONO (-1615 2660);
FORCEPROP 1 LAST PACK_TYPE SMLF
J 0
(-1575 2625);
DISPLAY 0.489362 (-1575 2625);
PAINT SKYBLUE (-1575 2625);
FORCEPROP 1 LAST VOLTAGE 4V
J 0
(-1575 2725);
DISPLAY 0.489362 (-1575 2725);
PAINT SKYBLUE (-1575 2725);
FORCEPROP 1 LAST VALUE 220UF
J 0
(-1575 2825);
DISPLAY 0.489362 (-1575 2825);
PAINT SKYBLUE (-1575 2825);
FORCEPROP 1 LAST TOLERANCE 20%
J 0
(-1575 2775);
DISPLAY 0.489362 (-1575 2775);
PAINT SKYBLUE (-1575 2775);
FORCEPROP 1 LAST MATERIAL SPCAP
J 0
(-1575 2675);
DISPLAY 0.489362 (-1575 2675);
PAINT SKYBLUE (-1575 2675);
FORCEPROP 1 LAST PART_NUMBER CH122KM8801
J 0
(-1575 2575);
DISPLAY 0.489362 (-1575 2575);
PAINT SKYBLUE (-1575 2575);
FORCEPROP 1 LAST PATH I153
J 0
(-1575 2925);
DISPLAY 0.978723 (-1575 2925);
DISPLAY INVISIBLE (-1575 2925);
FORCEPROP 2 LAST CDS_LIB pure_quanta
J 0
(-1625 2775);
DISPLAY INVISIBLE (-1625 2775);
FORCEADD Q_CAP..1
(-6150 5350);
FORCEPROP 1 LAST LOCATION PC375_1
J 0
(-6100 5500);
DISPLAY 0.489362 (-6100 5500);
PAINT SKYBLUE (-6100 5500);
FORCEPROP 0 LAST $SEC 1
J 0
(-6100 5500);
DISPLAY 0.680851 (-6100 5500);
PAINT MONO (-6100 5500);
DISPLAY INVISIBLE (-6100 5500);
FORCEPROP 0 LAST CDS_SEC 1
J 0
(-6100 5500);
DISPLAY 1.021277 (-6100 5500);
DISPLAY INVISIBLE (-6100 5500);
FORCEPROP 1 LASTPIN (-6150 5450) $PN 1
J 0
(-6140 5430);
DISPLAY 0.489362 (-6140 5430);
PAINT MONO (-6140 5430);
FORCEPROP 1 LASTPIN (-6150 5250) $PN 2
J 0
(-6140 5230);
DISPLAY 0.489362 (-6140 5230);
PAINT MONO (-6140 5230);
FORCEPROP 1 LAST MATERIAL X7R
J 0
(-6100 5300);
DISPLAY 0.489362 (-6100 5300);
PAINT SKYBLUE (-6100 5300);
FORCEPROP 1 LAST TOLERANCE 10%
J 0
(-6100 5350);
DISPLAY 0.489362 (-6100 5350);
PAINT SKYBLUE (-6100 5350);
FORCEPROP 1 LAST VALUE 0.1UF
J 0
(-6100 5450);
DISPLAY 0.489362 (-6100 5450);
PAINT SKYBLUE (-6100 5450);
FORCEPROP 1 LAST PART_NUMBER CH4104K1B00
J 0
(-6100 5200);
DISPLAY 0.489362 (-6100 5200);
PAINT SKYBLUE (-6100 5200);
FORCEPROP 1 LAST VOLTAGE 25V
J 0
(-6100 5400);
DISPLAY 0.489362 (-6100 5400);
PAINT SKYBLUE (-6100 5400);
FORCEPROP 1 LAST PACK_TYPE 0402
J 0
(-6100 5250);
DISPLAY 0.489362 (-6100 5250);
PAINT SKYBLUE (-6100 5250);
FORCEPROP 2 LAST CDS_LIB pure_quanta
J 0
(-6150 5350);
DISPLAY INVISIBLE (-6150 5350);
FORCEPROP 1 LAST PATH I154
J 0
(-6100 5500);
DISPLAY 0.978723 (-6100 5500);
PAINT WHITE (-6100 5500);
DISPLAY INVISIBLE (-6100 5500);
FORCEADD Q_CAP..1
(-6125 2725);
FORCEPROP 1 LAST LOCATION PC376_2
J 0
(-6075 2875);
DISPLAY 0.489362 (-6075 2875);
PAINT SKYBLUE (-6075 2875);
FORCEPROP 0 LAST $SEC 1
J 0
(-6075 2875);
DISPLAY 0.680851 (-6075 2875);
PAINT MONO (-6075 2875);
DISPLAY INVISIBLE (-6075 2875);
FORCEPROP 0 LAST CDS_SEC 1
J 0
(-6075 2875);
DISPLAY 1.021277 (-6075 2875);
DISPLAY INVISIBLE (-6075 2875);
FORCEPROP 1 LASTPIN (-6125 2825) $PN 1
J 0
(-6115 2805);
DISPLAY 0.489362 (-6115 2805);
PAINT MONO (-6115 2805);
FORCEPROP 1 LASTPIN (-6125 2625) $PN 2
J 0
(-6115 2605);
DISPLAY 0.489362 (-6115 2605);
PAINT MONO (-6115 2605);
FORCEPROP 1 LAST MATERIAL X7R
J 0
(-6075 2675);
DISPLAY 0.489362 (-6075 2675);
PAINT SKYBLUE (-6075 2675);
FORCEPROP 1 LAST TOLERANCE 10%
J 0
(-6075 2725);
DISPLAY 0.489362 (-6075 2725);
PAINT SKYBLUE (-6075 2725);
FORCEPROP 1 LAST VALUE 0.1UF
J 0
(-6075 2825);
DISPLAY 0.489362 (-6075 2825);
PAINT SKYBLUE (-6075 2825);
FORCEPROP 1 LAST PART_NUMBER CH4104K1B00
J 0
(-6075 2625);
DISPLAY 0.489362 (-6075 2625);
PAINT SKYBLUE (-6075 2625);
FORCEPROP 1 LAST VOLTAGE 25V
J 0
(-6075 2775);
DISPLAY 0.489362 (-6075 2775);
PAINT SKYBLUE (-6075 2775);
FORCEPROP 1 LAST PACK_TYPE 0402
J 0
(-6075 2575);
DISPLAY 0.489362 (-6075 2575);
PAINT SKYBLUE (-6075 2575);
FORCEPROP 2 LAST CDS_LIB pure_quanta
J 0
(-6125 2725);
DISPLAY INVISIBLE (-6125 2725);
FORCEPROP 1 LAST PATH I155
J 0
(-6075 2875);
DISPLAY 0.978723 (-6075 2875);
PAINT WHITE (-6075 2875);
DISPLAY INVISIBLE (-6075 2875);
FORCEADD Q_CAP..1
(-8700 4900);
FORCEPROP 1 LAST LOCATION PC369
J 0
(-8650 5000);
DISPLAY 0.489362 (-8650 5000);
PAINT SKYBLUE (-8650 5000);
FORCEPROP 0 LAST $SEC 1
J 0
(-8650 5050);
DISPLAY 0.680851 (-8650 5050);
PAINT MONO (-8650 5050);
DISPLAY INVISIBLE (-8650 5050);
FORCEPROP 0 LAST CDS_SEC 1
J 0
(-8650 5050);
DISPLAY 1.021277 (-8650 5050);
DISPLAY INVISIBLE (-8650 5050);
FORCEPROP 1 LASTPIN (-8700 5000) $PN 1
J 0
(-8690 4980);
DISPLAY 0.489362 (-8690 4980);
PAINT MONO (-8690 4980);
FORCEPROP 1 LASTPIN (-8700 4800) $PN 2
J 0
(-8690 4780);
DISPLAY 0.489362 (-8690 4780);
PAINT MONO (-8690 4780);
FORCEPROP 1 LAST MATERIAL X6S
J 0
(-8650 4800);
DISPLAY 0.489362 (-8650 4800);
PAINT SKYBLUE (-8650 4800);
FORCEPROP 1 LAST TOLERANCE 10%
J 0
(-8650 4850);
DISPLAY 0.489362 (-8650 4850);
PAINT SKYBLUE (-8650 4850);
FORCEPROP 1 LAST VALUE 2.2UF
J 0
(-8650 4950);
DISPLAY 0.489362 (-8650 4950);
PAINT SKYBLUE (-8650 4950);
FORCEPROP 1 LAST PART_NUMBER CH5222KEB01
J 0
(-8650 4750);
DISPLAY 0.489362 (-8650 4750);
PAINT SKYBLUE (-8650 4750);
FORCEPROP 1 LAST VOLTAGE 10V
J 0
(-8650 4900);
DISPLAY 0.489362 (-8650 4900);
PAINT SKYBLUE (-8650 4900);
FORCEPROP 1 LAST PACK_TYPE C0402
J 0
(-8650 4700);
DISPLAY 0.489362 (-8650 4700);
PAINT SKYBLUE (-8650 4700);
FORCEPROP 2 LAST CDS_LIB pure_quanta
J 0
(-8700 4900);
DISPLAY INVISIBLE (-8700 4900);
FORCEPROP 1 LAST PATH I156
J 0
(-8650 5050);
DISPLAY 0.978723 (-8650 5050);
PAINT WHITE (-8650 5050);
DISPLAY INVISIBLE (-8650 5050);
FORCEADD UNIVERSAL_GND..1
(-8700 4700);
FORCEPROP 3 LASTPIN (-8700 4750) SIG_NAME GND\g
J 0
(-8690 4760);
DISPLAY 0.659574 (-8690 4760);
PAINT MONO (-8690 4760);
DISPLAY INVISIBLE (-8690 4760);
FORCEPROP 2 LAST CDS_LIB pure_quanta_power
J 0
(-8700 4700);
DISPLAY INVISIBLE (-8700 4700);
FORCEPROP 1 LAST PATH I157
J 0
(-8625 4700);
DISPLAY 0.872340 (-8625 4700);
PAINT AQUA (-8625 4700);
DISPLAY INVISIBLE (-8625 4700);
FORCEPROP 1 LAST HDL_POWER GND
J 1
(-8675 4625);
DISPLAY 0.872340 (-8675 4625);
PAINT GREEN (-8675 4625);
DISPLAY INVISIBLE (-8675 4625);
FORCEADD UNIVERSAL_GND..1
(-8350 5200);
FORCEPROP 3 LASTPIN (-8350 5250) SIG_NAME GND\g
J 0
(-8340 5260);
DISPLAY 0.659574 (-8340 5260);
PAINT MONO (-8340 5260);
DISPLAY INVISIBLE (-8340 5260);
FORCEPROP 2 LAST CDS_LIB pure_quanta_power
J 0
(-8350 5200);
DISPLAY INVISIBLE (-8350 5200);
FORCEPROP 1 LAST PATH I158
J 0
(-8275 5200);
DISPLAY 0.872340 (-8275 5200);
PAINT AQUA (-8275 5200);
DISPLAY INVISIBLE (-8275 5200);
FORCEPROP 1 LAST HDL_POWER GND
J 1
(-8325 5125);
DISPLAY 0.872340 (-8325 5125);
PAINT GREEN (-8325 5125);
DISPLAY INVISIBLE (-8325 5125);
FORCEADD Q_RES..2
(-8700 5450);
FORCEPROP 1 LAST LOCATION PR256
J 0
(-8655 5575);
DISPLAY 0.489362 (-8655 5575);
PAINT SKYBLUE (-8655 5575);
FORCEPROP 0 LAST $SEC 1
J 0
(-8650 5625);
DISPLAY 0.680851 (-8650 5625);
PAINT MONO (-8650 5625);
DISPLAY INVISIBLE (-8650 5625);
FORCEPROP 0 LAST CDS_SEC 1
J 0
(-8650 5625);
DISPLAY 1.021277 (-8650 5625);
DISPLAY INVISIBLE (-8650 5625);
FORCEPROP 1 LASTPIN (-8700 5550) $PN 1
J 0
(-8695 5512);
DISPLAY 0.489362 (-8695 5512);
PAINT MONO (-8695 5512);
FORCEPROP 1 LASTPIN (-8700 5350) $PN 2
J 0
(-8695 5360);
DISPLAY 0.489362 (-8695 5360);
PAINT MONO (-8695 5360);
FORCEPROP 1 LAST PART_NUMBER CS-2202FB00
J 0
(-8650 5325);
DISPLAY 0.489362 (-8650 5325);
PAINT SKYBLUE (-8650 5325);
FORCEPROP 1 LAST WATTAGE 1/16W
J 0
(-8650 5425);
DISPLAY 0.489362 (-8650 5425);
PAINT SKYBLUE (-8650 5425);
FORCEPROP 1 LAST MATERIAL CHIP
J 0
(-8650 5375);
DISPLAY 0.489362 (-8650 5375);
PAINT SKYBLUE (-8650 5375);
FORCEPROP 1 LAST TOLERANCE 1%
J 0
(-8650 5475);
DISPLAY 0.489362 (-8650 5475);
PAINT SKYBLUE (-8650 5475);
FORCEPROP 1 LAST VALUE 2.2
J 0
(-8650 5525);
DISPLAY 0.489362 (-8650 5525);
PAINT SKYBLUE (-8650 5525);
FORCEPROP 1 LAST PACK_TYPE 0402LF
J 0
(-8650 5275);
DISPLAY 0.489362 (-8650 5275);
PAINT SKYBLUE (-8650 5275);
FORCEPROP 2 LAST CDS_LIB pure_quanta
J 0
(-8700 5450);
DISPLAY INVISIBLE (-8700 5450);
FORCEPROP 1 LAST PATH I159
J 0
(-8650 5625);
DISPLAY 0.978723 (-8650 5625);
PAINT WHITE (-8650 5625);
DISPLAY INVISIBLE (-8650 5625);
FORCEADD OFFPAGE..5
(-8275 3950);
FORCEPROP 2 LAST $XR3 193 
J 0
(-8680 3914);
DISPLAY 0.638298 (-8680 3914);
PAINT MONO (-8680 3914);
FORCEPROP 2 LAST $XR2 196 
J 0
(-8560 3914);
DISPLAY 0.638298 (-8560 3914);
PAINT MONO (-8560 3914);
FORCEPROP 2 LAST $XR1 195 
J 0
(-8680 3950);
DISPLAY 0.638298 (-8680 3950);
PAINT MONO (-8680 3950);
FORCEPROP 2 LAST $XR0 194 
J 0
(-8560 3950);
DISPLAY 0.638298 (-8560 3950);
PAINT MONO (-8560 3950);
FORCEPROP 1 LAST COMMENT_BODY TRUE
J 0
(-8175 3875);
DISPLAY 0.872340 (-8175 3875);
PAINT GREEN (-8175 3875);
DISPLAY INVISIBLE (-8175 3875);
FORCEPROP 1 LAST OFFPAGE TRUE
J 0
(-7950 3825);
DISPLAY 0.872340 (-7950 3825);
PAINT GREEN (-7950 3825);
DISPLAY INVISIBLE (-7950 3825);
FORCEPROP 2 LAST CDS_LIB standard
J 0
(-8275 3950);
DISPLAY INVISIBLE (-8275 3950);
FORCEPROP 2 LAST PATH I16
J 0
(-8550 4025);
DISPLAY 1.021277 (-8550 4025);
DISPLAY INVISIBLE (-8550 4025);
FORCEADD Q_CAP..1
(-8350 5475);
FORCEPROP 1 LAST LOCATION PC371_C1P1_1
J 0
(-8300 5575);
DISPLAY 0.489362 (-8300 5575);
PAINT SKYBLUE (-8300 5575);
FORCEPROP 0 LAST $SEC 1
J 0
(-8300 5625);
DISPLAY 0.680851 (-8300 5625);
PAINT MONO (-8300 5625);
DISPLAY INVISIBLE (-8300 5625);
FORCEPROP 0 LAST CDS_SEC 1
J 0
(-8300 5625);
DISPLAY 1.021277 (-8300 5625);
DISPLAY INVISIBLE (-8300 5625);
FORCEPROP 1 LASTPIN (-8350 5575) $PN 1
J 0
(-8340 5555);
DISPLAY 0.489362 (-8340 5555);
PAINT MONO (-8340 5555);
FORCEPROP 1 LASTPIN (-8350 5375) $PN 2
J 0
(-8340 5355);
DISPLAY 0.489362 (-8340 5355);
PAINT MONO (-8340 5355);
FORCEPROP 1 LAST MATERIAL X6S
J 0
(-8300 5375);
DISPLAY 0.489362 (-8300 5375);
PAINT SKYBLUE (-8300 5375);
FORCEPROP 1 LAST TOLERANCE 10%
J 0
(-8300 5425);
DISPLAY 0.489362 (-8300 5425);
PAINT SKYBLUE (-8300 5425);
FORCEPROP 1 LAST VALUE 2.2UF
J 0
(-8300 5525);
DISPLAY 0.489362 (-8300 5525);
PAINT SKYBLUE (-8300 5525);
FORCEPROP 1 LAST PART_NUMBER CH5222KEB01
J 0
(-8300 5325);
DISPLAY 0.489362 (-8300 5325);
PAINT SKYBLUE (-8300 5325);
FORCEPROP 1 LAST VOLTAGE 10V
J 0
(-8300 5475);
DISPLAY 0.489362 (-8300 5475);
PAINT SKYBLUE (-8300 5475);
FORCEPROP 1 LAST PACK_TYPE C0402
J 0
(-8300 5275);
DISPLAY 0.489362 (-8300 5275);
PAINT SKYBLUE (-8300 5275);
FORCEPROP 2 LAST CDS_LIB pure_quanta
J 0
(-8350 5475);
DISPLAY INVISIBLE (-8350 5475);
FORCEPROP 1 LAST PATH I160
J 0
(-8300 5625);
DISPLAY 0.978723 (-8300 5625);
PAINT WHITE (-8300 5625);
DISPLAY INVISIBLE (-8300 5625);
FORCEADD VCC_CORE..1
(-8500 6050);
FORCEPROP 3 LASTPIN (-8500 6000) SIG_NAME PVDDCR_CPU1_P1_PVCC\g
J 0
(-8490 6010);
DISPLAY 0.659574 (-8490 6010);
PAINT MONO (-8490 6010);
DISPLAY INVISIBLE (-8490 6010);
FORCEPROP 1 LAST HDL_POWER PVDDCR_CPU1_P1_PVCC
J 1
(-8500 6100);
DISPLAY 0.489362 (-8500 6100);
PAINT GREEN (-8500 6100);
FORCEPROP 2 LAST CDS_LIB pure_quanta_power
J 0
(-8500 6050);
DISPLAY INVISIBLE (-8500 6050);
FORCEPROP 1 LAST PATH I161
J 0
(-8450 6075);
DISPLAY 0.872340 (-8450 6075);
PAINT AQUA (-8450 6075);
DISPLAY INVISIBLE (-8450 6075);
FORCEADD Q_CAP..1
(-8600 2250);
FORCEPROP 1 LAST LOCATION PC370
J 0
(-8550 2350);
DISPLAY 0.489362 (-8550 2350);
PAINT SKYBLUE (-8550 2350);
FORCEPROP 0 LAST $SEC 1
J 0
(-8550 2400);
DISPLAY 0.680851 (-8550 2400);
PAINT MONO (-8550 2400);
DISPLAY INVISIBLE (-8550 2400);
FORCEPROP 0 LAST CDS_SEC 1
J 0
(-8550 2400);
DISPLAY 1.021277 (-8550 2400);
DISPLAY INVISIBLE (-8550 2400);
FORCEPROP 1 LASTPIN (-8600 2350) $PN 1
J 0
(-8590 2330);
DISPLAY 0.489362 (-8590 2330);
PAINT MONO (-8590 2330);
FORCEPROP 1 LASTPIN (-8600 2150) $PN 2
J 0
(-8590 2130);
DISPLAY 0.489362 (-8590 2130);
PAINT MONO (-8590 2130);
FORCEPROP 1 LAST MATERIAL X6S
J 0
(-8550 2150);
DISPLAY 0.489362 (-8550 2150);
PAINT SKYBLUE (-8550 2150);
FORCEPROP 1 LAST TOLERANCE 10%
J 0
(-8550 2200);
DISPLAY 0.489362 (-8550 2200);
PAINT SKYBLUE (-8550 2200);
FORCEPROP 1 LAST VALUE 2.2UF
J 0
(-8550 2300);
DISPLAY 0.489362 (-8550 2300);
PAINT SKYBLUE (-8550 2300);
FORCEPROP 1 LAST PART_NUMBER CH5222KEB01
J 0
(-8550 2100);
DISPLAY 0.489362 (-8550 2100);
PAINT SKYBLUE (-8550 2100);
FORCEPROP 1 LAST VOLTAGE 10V
J 0
(-8550 2250);
DISPLAY 0.489362 (-8550 2250);
PAINT SKYBLUE (-8550 2250);
FORCEPROP 1 LAST PACK_TYPE C0402
J 0
(-8550 2050);
DISPLAY 0.489362 (-8550 2050);
PAINT SKYBLUE (-8550 2050);
FORCEPROP 2 LAST CDS_LIB pure_quanta
J 0
(-8600 2250);
DISPLAY INVISIBLE (-8600 2250);
FORCEPROP 1 LAST PATH I162
J 0
(-8550 2400);
DISPLAY 0.978723 (-8550 2400);
PAINT WHITE (-8550 2400);
DISPLAY INVISIBLE (-8550 2400);
FORCEADD UNIVERSAL_GND..1
(-8600 2050);
FORCEPROP 3 LASTPIN (-8600 2100) SIG_NAME GND\g
J 0
(-8590 2110);
DISPLAY 0.659574 (-8590 2110);
PAINT MONO (-8590 2110);
DISPLAY INVISIBLE (-8590 2110);
FORCEPROP 2 LAST CDS_LIB pure_quanta_power
J 0
(-8600 2050);
DISPLAY INVISIBLE (-8600 2050);
FORCEPROP 1 LAST PATH I163
J 0
(-8525 2050);
DISPLAY 0.872340 (-8525 2050);
PAINT AQUA (-8525 2050);
DISPLAY INVISIBLE (-8525 2050);
FORCEPROP 1 LAST HDL_POWER GND
J 1
(-8575 1975);
DISPLAY 0.872340 (-8575 1975);
PAINT GREEN (-8575 1975);
DISPLAY INVISIBLE (-8575 1975);
FORCEADD UNIVERSAL_GND..1
(-8250 2550);
FORCEPROP 3 LASTPIN (-8250 2600) SIG_NAME GND\g
J 0
(-8240 2610);
DISPLAY 0.659574 (-8240 2610);
PAINT MONO (-8240 2610);
DISPLAY INVISIBLE (-8240 2610);
FORCEPROP 2 LAST CDS_LIB pure_quanta_power
J 0
(-8250 2550);
DISPLAY INVISIBLE (-8250 2550);
FORCEPROP 1 LAST PATH I164
J 0
(-8175 2550);
DISPLAY 0.872340 (-8175 2550);
PAINT AQUA (-8175 2550);
DISPLAY INVISIBLE (-8175 2550);
FORCEPROP 1 LAST HDL_POWER GND
J 1
(-8225 2475);
DISPLAY 0.872340 (-8225 2475);
PAINT GREEN (-8225 2475);
DISPLAY INVISIBLE (-8225 2475);
FORCEADD Q_RES..2
(-8600 2800);
FORCEPROP 1 LAST LOCATION PR257
J 0
(-8555 2925);
DISPLAY 0.489362 (-8555 2925);
PAINT SKYBLUE (-8555 2925);
FORCEPROP 0 LAST $SEC 1
J 0
(-8550 2975);
DISPLAY 0.680851 (-8550 2975);
PAINT MONO (-8550 2975);
DISPLAY INVISIBLE (-8550 2975);
FORCEPROP 0 LAST CDS_SEC 1
J 0
(-8550 2975);
DISPLAY 1.021277 (-8550 2975);
DISPLAY INVISIBLE (-8550 2975);
FORCEPROP 1 LASTPIN (-8600 2900) $PN 1
J 0
(-8595 2862);
DISPLAY 0.489362 (-8595 2862);
PAINT MONO (-8595 2862);
FORCEPROP 1 LASTPIN (-8600 2700) $PN 2
J 0
(-8595 2710);
DISPLAY 0.489362 (-8595 2710);
PAINT MONO (-8595 2710);
FORCEPROP 1 LAST WATTAGE 1/16W
J 0
(-8550 2775);
DISPLAY 0.489362 (-8550 2775);
PAINT SKYBLUE (-8550 2775);
FORCEPROP 1 LAST MATERIAL CHIP
J 0
(-8550 2725);
DISPLAY 0.489362 (-8550 2725);
PAINT SKYBLUE (-8550 2725);
FORCEPROP 1 LAST TOLERANCE 1%
J 0
(-8550 2825);
DISPLAY 0.489362 (-8550 2825);
PAINT SKYBLUE (-8550 2825);
FORCEPROP 1 LAST VALUE 2.2
J 0
(-8550 2875);
DISPLAY 0.489362 (-8550 2875);
PAINT SKYBLUE (-8550 2875);
FORCEPROP 1 LAST PART_NUMBER CS-2202FB00
J 0
(-8550 2675);
DISPLAY 0.489362 (-8550 2675);
PAINT SKYBLUE (-8550 2675);
FORCEPROP 1 LAST PACK_TYPE 0402LF
J 0
(-8550 2625);
DISPLAY 0.489362 (-8550 2625);
PAINT SKYBLUE (-8550 2625);
FORCEPROP 2 LAST CDS_LIB pure_quanta
J 0
(-8600 2800);
DISPLAY INVISIBLE (-8600 2800);
FORCEPROP 1 LAST PATH I165
J 0
(-8550 2975);
DISPLAY 0.978723 (-8550 2975);
PAINT WHITE (-8550 2975);
DISPLAY INVISIBLE (-8550 2975);
FORCEADD Q_CAP..1
(-8250 2825);
FORCEPROP 1 LAST LOCATION PC372_C1P1_2
J 0
(-8200 2925);
DISPLAY 0.489362 (-8200 2925);
PAINT SKYBLUE (-8200 2925);
FORCEPROP 0 LAST $SEC 1
J 0
(-8200 2975);
DISPLAY 0.680851 (-8200 2975);
PAINT MONO (-8200 2975);
DISPLAY INVISIBLE (-8200 2975);
FORCEPROP 0 LAST CDS_SEC 1
J 0
(-8200 2975);
DISPLAY 1.021277 (-8200 2975);
DISPLAY INVISIBLE (-8200 2975);
FORCEPROP 1 LASTPIN (-8250 2925) $PN 1
J 0
(-8240 2905);
DISPLAY 0.489362 (-8240 2905);
PAINT MONO (-8240 2905);
FORCEPROP 1 LASTPIN (-8250 2725) $PN 2
J 0
(-8240 2705);
DISPLAY 0.489362 (-8240 2705);
PAINT MONO (-8240 2705);
FORCEPROP 1 LAST MATERIAL X6S
J 0
(-8200 2725);
DISPLAY 0.489362 (-8200 2725);
PAINT SKYBLUE (-8200 2725);
FORCEPROP 1 LAST TOLERANCE 10%
J 0
(-8200 2775);
DISPLAY 0.489362 (-8200 2775);
PAINT SKYBLUE (-8200 2775);
FORCEPROP 1 LAST VALUE 2.2UF
J 0
(-8200 2875);
DISPLAY 0.489362 (-8200 2875);
PAINT SKYBLUE (-8200 2875);
FORCEPROP 1 LAST PART_NUMBER CH5222KEB01
J 0
(-8200 2675);
DISPLAY 0.489362 (-8200 2675);
PAINT SKYBLUE (-8200 2675);
FORCEPROP 1 LAST VOLTAGE 10V
J 0
(-8200 2825);
DISPLAY 0.489362 (-8200 2825);
PAINT SKYBLUE (-8200 2825);
FORCEPROP 1 LAST PACK_TYPE C0402
J 0
(-8200 2625);
DISPLAY 0.489362 (-8200 2625);
PAINT SKYBLUE (-8200 2625);
FORCEPROP 2 LAST CDS_LIB pure_quanta
J 0
(-8250 2825);
DISPLAY INVISIBLE (-8250 2825);
FORCEPROP 1 LAST PATH I166
J 0
(-8200 2975);
DISPLAY 0.978723 (-8200 2975);
PAINT WHITE (-8200 2975);
DISPLAY INVISIBLE (-8200 2975);
FORCEADD UNIVERSAL_GND..1
(-9350 3875);
FORCEPROP 3 LASTPIN (-9350 3925) SIG_NAME GND\g
J 0
(-9340 3935);
DISPLAY 0.659574 (-9340 3935);
PAINT MONO (-9340 3935);
DISPLAY INVISIBLE (-9340 3935);
FORCEPROP 2 LAST CDS_LIB pure_quanta_power
J 0
(-9350 3875);
DISPLAY INVISIBLE (-9350 3875);
FORCEPROP 1 LAST PATH I168
J 0
(-9275 3875);
DISPLAY 0.872340 (-9275 3875);
PAINT AQUA (-9275 3875);
DISPLAY INVISIBLE (-9275 3875);
FORCEPROP 1 LAST HDL_POWER GND
J 1
(-9325 3800);
DISPLAY 0.872340 (-9325 3800);
PAINT GREEN (-9325 3800);
DISPLAY INVISIBLE (-9325 3800);
FORCEADD UNIVERSAL_GND..1
(-9375 1250);
FORCEPROP 3 LASTPIN (-9375 1300) SIG_NAME GND\g
J 0
(-9365 1310);
DISPLAY 0.659574 (-9365 1310);
PAINT MONO (-9365 1310);
DISPLAY INVISIBLE (-9365 1310);
FORCEPROP 2 LAST CDS_LIB pure_quanta_power
J 0
(-9375 1250);
DISPLAY INVISIBLE (-9375 1250);
FORCEPROP 1 LAST PATH I169
J 0
(-9300 1250);
DISPLAY 0.872340 (-9300 1250);
PAINT AQUA (-9300 1250);
DISPLAY INVISIBLE (-9300 1250);
FORCEPROP 1 LAST HDL_POWER GND
J 1
(-9350 1175);
DISPLAY 0.872340 (-9350 1175);
PAINT GREEN (-9350 1175);
DISPLAY INVISIBLE (-9350 1175);
FORCEADD Q_CAPP..1
(-2925 2775);
FORCEPROP 1 LAST LOCATION PC106
J 0
(-2875 2875);
DISPLAY 0.489362 (-2875 2875);
PAINT SKYBLUE (-2875 2875);
FORCEPROP 0 LAST $SEC 1
J 0
(-2875 2925);
DISPLAY 0.680851 (-2875 2925);
PAINT MONO (-2875 2925);
DISPLAY INVISIBLE (-2875 2925);
FORCEPROP 0 LAST CDS_SEC 1
J 0
(-2875 2925);
DISPLAY 1.021277 (-2875 2925);
DISPLAY INVISIBLE (-2875 2925);
FORCEPROP 1 LASTPIN (-2925 2875) $PN 1
J 0
(-2915 2860);
DISPLAY 0.489362 (-2915 2860);
PAINT MONO (-2915 2860);
FORCEPROP 1 LASTPIN (-2925 2675) $PN 2
J 0
(-2915 2660);
DISPLAY 0.489362 (-2915 2660);
PAINT MONO (-2915 2660);
FORCEPROP 1 LAST VOLTAGE 4V
J 0
(-2875 2725);
DISPLAY 0.489362 (-2875 2725);
PAINT SKYBLUE (-2875 2725);
FORCEPROP 1 LAST TOLERANCE 20%
J 0
(-2875 2775);
DISPLAY 0.489362 (-2875 2775);
PAINT SKYBLUE (-2875 2775);
FORCEPROP 1 LAST PACK_TYPE SMLF
J 0
(-2875 2625);
DISPLAY 0.489362 (-2875 2625);
PAINT SKYBLUE (-2875 2625);
FORCEPROP 1 LAST MATERIAL SPCAP
J 0
(-2875 2675);
DISPLAY 0.489362 (-2875 2675);
PAINT SKYBLUE (-2875 2675);
FORCEPROP 1 LAST PART_NUMBER CH122KM8801
J 0
(-2875 2575);
DISPLAY 0.489362 (-2875 2575);
PAINT SKYBLUE (-2875 2575);
FORCEPROP 1 LAST VALUE 220UF
J 0
(-2875 2825);
DISPLAY 0.489362 (-2875 2825);
PAINT SKYBLUE (-2875 2825);
FORCEPROP 1 LAST PATH I170
J 0
(-2875 2925);
DISPLAY 0.978723 (-2875 2925);
DISPLAY INVISIBLE (-2875 2925);
FORCEPROP 2 LAST CDS_LIB pure_quanta
J 0
(-2925 2775);
DISPLAY INVISIBLE (-2925 2775);
FORCEADD OFFPAGE..6
R 2
(-2350 1575);
FORCEPROP 2 LAST $XR0 195 
J 0
(-2136 1575);
DISPLAY 0.638298 (-2136 1575);
PAINT MONO (-2136 1575);
FORCEPROP 1 LAST OFFPAGE TRUE
J 2
(-2675 1450);
DISPLAY 0.872340 (-2675 1450);
PAINT GREEN (-2675 1450);
DISPLAY INVISIBLE (-2675 1450);
FORCEPROP 1 LAST COMMENT_BODY TRUE
J 2
(-2450 1500);
DISPLAY 0.872340 (-2450 1500);
PAINT GREEN (-2450 1500);
DISPLAY INVISIBLE (-2450 1500);
FORCEPROP 2 LAST CDS_LIB standard
J 0
(-2350 1575);
DISPLAY INVISIBLE (-2350 1575);
FORCEPROP 2 LAST PATH I171
J 0
(-2150 1650);
DISPLAY 1.021277 (-2150 1650);
DISPLAY INVISIBLE (-2150 1650);
FORCEADD UNIVERSAL_GND..1
(-5450 3500);
FORCEPROP 3 LASTPIN (-5450 3550) SIG_NAME GND\g
J 0
(-5440 3560);
DISPLAY 0.659574 (-5440 3560);
PAINT MONO (-5440 3560);
DISPLAY INVISIBLE (-5440 3560);
FORCEPROP 2 LAST CDS_LIB pure_quanta_power
J 0
(-5450 3500);
DISPLAY INVISIBLE (-5450 3500);
FORCEPROP 1 LAST PATH I172
J 0
(-5375 3500);
DISPLAY 0.872340 (-5375 3500);
PAINT AQUA (-5375 3500);
DISPLAY INVISIBLE (-5375 3500);
FORCEPROP 1 LAST HDL_POWER GND
J 1
(-5425 3425);
DISPLAY 0.872340 (-5425 3425);
PAINT GREEN (-5425 3425);
DISPLAY INVISIBLE (-5425 3425);
FORCEADD Q_RES..2
(-5450 3725);
FORCEPROP 1 LAST LOCATION PR512
J 0
(-5405 3850);
DISPLAY 0.489362 (-5405 3850);
PAINT SKYBLUE (-5405 3850);
FORCEPROP 0 LAST $SEC 1
J 0
(-5400 3900);
DISPLAY 0.680851 (-5400 3900);
PAINT MONO (-5400 3900);
DISPLAY INVISIBLE (-5400 3900);
FORCEPROP 0 LAST CDS_SEC 1
J 0
(-5400 3900);
DISPLAY 1.021277 (-5400 3900);
DISPLAY INVISIBLE (-5400 3900);
FORCEPROP 1 LASTPIN (-5450 3825) $PN 1
J 0
(-5445 3787);
DISPLAY 0.489362 (-5445 3787);
PAINT MONO (-5445 3787);
FORCEPROP 1 LASTPIN (-5450 3625) $PN 2
J 0
(-5445 3635);
DISPLAY 0.489362 (-5445 3635);
PAINT MONO (-5445 3635);
FORCEPROP 1 LAST WATTAGE 1/8W
J 0
(-5410 3700);
DISPLAY 0.489362 (-5410 3700);
PAINT SKYBLUE (-5410 3700);
FORCEPROP 1 LAST PART_NUMBER CS-1504FB00
J 0
(-5410 3600);
DISPLAY 0.489362 (-5410 3600);
PAINT SKYBLUE (-5410 3600);
FORCEPROP 1 LAST MATERIAL EMPTY
J 0
(-5410 3650);
DISPLAY 0.489362 (-5410 3650);
PAINT RED (-5410 3650);
FORCEPROP 1 LAST TOLERANCE 1%
J 0
(-5405 3750);
DISPLAY 0.489362 (-5405 3750);
PAINT SKYBLUE (-5405 3750);
FORCEPROP 1 LAST VALUE 1.5
J 0
(-5405 3800);
DISPLAY 0.489362 (-5405 3800);
PAINT SKYBLUE (-5405 3800);
FORCEPROP 1 LAST PACK_TYPE 0402LF
J 0
(-5410 3550);
DISPLAY 0.489362 (-5410 3550);
PAINT SKYBLUE (-5410 3550);
FORCEPROP 2 LAST CDS_LIB pure_quanta
J 0
(-5450 3725);
DISPLAY INVISIBLE (-5450 3725);
FORCEPROP 1 LAST PATH I173
J 0
(-5400 3900);
DISPLAY 0.978723 (-5400 3900);
PAINT WHITE (-5400 3900);
DISPLAY INVISIBLE (-5400 3900);
FORCEADD Q_CAP..1
(-5450 4250);
FORCEPROP 1 LAST LOCATION PC201
J 0
(-5400 4350);
DISPLAY 0.489362 (-5400 4350);
PAINT SKYBLUE (-5400 4350);
FORCEPROP 0 LAST $SEC 1
J 0
(-5400 4400);
DISPLAY 0.680851 (-5400 4400);
PAINT MONO (-5400 4400);
DISPLAY INVISIBLE (-5400 4400);
FORCEPROP 0 LAST CDS_SEC 1
J 0
(-5400 4400);
DISPLAY 1.021277 (-5400 4400);
DISPLAY INVISIBLE (-5400 4400);
FORCEPROP 1 LASTPIN (-5450 4350) $PN 1
J 0
(-5440 4330);
DISPLAY 0.489362 (-5440 4330);
PAINT MONO (-5440 4330);
FORCEPROP 1 LASTPIN (-5450 4150) $PN 2
J 0
(-5440 4130);
DISPLAY 0.489362 (-5440 4130);
PAINT MONO (-5440 4130);
FORCEPROP 1 LAST MATERIAL EMPTY
J 0
(-5400 4150);
DISPLAY 0.489362 (-5400 4150);
PAINT RED (-5400 4150);
FORCEPROP 1 LAST TOLERANCE 10%
J 0
(-5400 4200);
DISPLAY 0.489362 (-5400 4200);
PAINT SKYBLUE (-5400 4200);
FORCEPROP 1 LAST VALUE 560PF
J 0
(-5400 4300);
DISPLAY 0.489362 (-5400 4300);
PAINT SKYBLUE (-5400 4300);
FORCEPROP 1 LAST PART_NUMBER CH1566K1B09
J 0
(-5400 4100);
DISPLAY 0.489362 (-5400 4100);
PAINT SKYBLUE (-5400 4100);
FORCEPROP 1 LAST VOLTAGE 50V
J 0
(-5400 4250);
DISPLAY 0.489362 (-5400 4250);
PAINT SKYBLUE (-5400 4250);
FORCEPROP 1 LAST PACK_TYPE C0402
J 0
(-5400 4050);
DISPLAY 0.489362 (-5400 4050);
PAINT SKYBLUE (-5400 4050);
FORCEPROP 2 LAST CDS_LIB pure_quanta
J 0
(-5450 4250);
DISPLAY INVISIBLE (-5450 4250);
FORCEPROP 1 LAST PATH I174
J 0
(-5400 4400);
DISPLAY 0.978723 (-5400 4400);
PAINT WHITE (-5400 4400);
DISPLAY INVISIBLE (-5400 4400);
FORCEADD UNIVERSAL_GND..1
(-5500 875);
FORCEPROP 3 LASTPIN (-5500 925) SIG_NAME GND\g
J 0
(-5490 935);
DISPLAY 0.659574 (-5490 935);
PAINT MONO (-5490 935);
DISPLAY INVISIBLE (-5490 935);
FORCEPROP 2 LAST CDS_LIB pure_quanta_power
J 0
(-5500 875);
DISPLAY INVISIBLE (-5500 875);
FORCEPROP 1 LAST PATH I175
J 0
(-5425 875);
DISPLAY 0.872340 (-5425 875);
PAINT AQUA (-5425 875);
DISPLAY INVISIBLE (-5425 875);
FORCEPROP 1 LAST HDL_POWER GND
J 1
(-5475 800);
DISPLAY 0.872340 (-5475 800);
PAINT GREEN (-5475 800);
DISPLAY INVISIBLE (-5475 800);
FORCEADD Q_RES..2
(-5500 1100);
FORCEPROP 1 LAST LOCATION PR513
J 0
(-5455 1225);
DISPLAY 0.489362 (-5455 1225);
PAINT SKYBLUE (-5455 1225);
FORCEPROP 0 LAST $SEC 1
J 0
(-5450 1275);
DISPLAY 0.680851 (-5450 1275);
PAINT MONO (-5450 1275);
DISPLAY INVISIBLE (-5450 1275);
FORCEPROP 0 LAST CDS_SEC 1
J 0
(-5450 1275);
DISPLAY 1.021277 (-5450 1275);
DISPLAY INVISIBLE (-5450 1275);
FORCEPROP 1 LASTPIN (-5500 1200) $PN 1
J 0
(-5495 1162);
DISPLAY 0.489362 (-5495 1162);
PAINT MONO (-5495 1162);
FORCEPROP 1 LASTPIN (-5500 1000) $PN 2
J 0
(-5495 1010);
DISPLAY 0.489362 (-5495 1010);
PAINT MONO (-5495 1010);
FORCEPROP 1 LAST WATTAGE 1/8W
J 0
(-5460 1075);
DISPLAY 0.489362 (-5460 1075);
PAINT SKYBLUE (-5460 1075);
FORCEPROP 1 LAST MATERIAL EMPTY
J 0
(-5460 1025);
DISPLAY 0.489362 (-5460 1025);
PAINT RED (-5460 1025);
FORCEPROP 1 LAST TOLERANCE 1%
J 0
(-5455 1125);
DISPLAY 0.489362 (-5455 1125);
PAINT SKYBLUE (-5455 1125);
FORCEPROP 1 LAST VALUE 1.5
J 0
(-5455 1175);
DISPLAY 0.489362 (-5455 1175);
PAINT SKYBLUE (-5455 1175);
FORCEPROP 1 LAST PART_NUMBER CS-1504FB00
J 0
(-5460 975);
DISPLAY 0.489362 (-5460 975);
PAINT SKYBLUE (-5460 975);
FORCEPROP 1 LAST PACK_TYPE 0402LF
J 0
(-5460 925);
DISPLAY 0.489362 (-5460 925);
PAINT SKYBLUE (-5460 925);
FORCEPROP 2 LAST CDS_LIB pure_quanta
J 0
(-5500 1100);
DISPLAY INVISIBLE (-5500 1100);
FORCEPROP 1 LAST PATH I176
J 0
(-5450 1275);
DISPLAY 0.978723 (-5450 1275);
PAINT WHITE (-5450 1275);
DISPLAY INVISIBLE (-5450 1275);
FORCEADD Q_CAP..1
(-5500 1650);
FORCEPROP 1 LAST LOCATION PC202
J 0
(-5450 1750);
DISPLAY 0.489362 (-5450 1750);
PAINT SKYBLUE (-5450 1750);
FORCEPROP 0 LAST $SEC 1
J 0
(-5450 1800);
DISPLAY 0.680851 (-5450 1800);
PAINT MONO (-5450 1800);
DISPLAY INVISIBLE (-5450 1800);
FORCEPROP 0 LAST CDS_SEC 1
J 0
(-5450 1800);
DISPLAY 1.021277 (-5450 1800);
DISPLAY INVISIBLE (-5450 1800);
FORCEPROP 1 LASTPIN (-5500 1750) $PN 1
J 0
(-5490 1730);
DISPLAY 0.489362 (-5490 1730);
PAINT MONO (-5490 1730);
FORCEPROP 1 LASTPIN (-5500 1550) $PN 2
J 0
(-5490 1530);
DISPLAY 0.489362 (-5490 1530);
PAINT MONO (-5490 1530);
FORCEPROP 1 LAST TOLERANCE 10%
J 0
(-5450 1600);
DISPLAY 0.489362 (-5450 1600);
PAINT SKYBLUE (-5450 1600);
FORCEPROP 1 LAST MATERIAL EMPTY
J 0
(-5450 1550);
DISPLAY 0.489362 (-5450 1550);
PAINT RED (-5450 1550);
FORCEPROP 1 LAST PART_NUMBER CH1566K1B09
J 0
(-5450 1500);
DISPLAY 0.489362 (-5450 1500);
PAINT SKYBLUE (-5450 1500);
FORCEPROP 1 LAST VALUE 560PF
J 0
(-5450 1700);
DISPLAY 0.489362 (-5450 1700);
PAINT SKYBLUE (-5450 1700);
FORCEPROP 1 LAST VOLTAGE 50V
J 0
(-5450 1650);
DISPLAY 0.489362 (-5450 1650);
PAINT SKYBLUE (-5450 1650);
FORCEPROP 1 LAST PACK_TYPE C0402
J 0
(-5450 1450);
DISPLAY 0.489362 (-5450 1450);
PAINT SKYBLUE (-5450 1450);
FORCEPROP 2 LAST CDS_LIB pure_quanta
J 0
(-5500 1650);
DISPLAY INVISIBLE (-5500 1650);
FORCEPROP 1 LAST PATH I177
J 0
(-5450 1800);
DISPLAY 0.978723 (-5450 1800);
PAINT WHITE (-5450 1800);
DISPLAY INVISIBLE (-5450 1800);
FORCEADD OFFPAGE..6
(-4675 4200);
FORCEPROP 2 LAST $XR0 196 
J 0
(-4985 4200);
DISPLAY 0.638298 (-4985 4200);
PAINT MONO (-4985 4200);
FORCEPROP 1 LAST COMMENT_BODY TRUE
J 0
(-4575 4125);
DISPLAY 0.872340 (-4575 4125);
PAINT GREEN (-4575 4125);
DISPLAY INVISIBLE (-4575 4125);
FORCEPROP 2 LAST CDS_LIB standard
J 2
(-4675 4200);
DISPLAY INVISIBLE (-4675 4200);
FORCEPROP 2 LAST PATH I178
J 2
(-4875 4275);
DISPLAY 1.021277 (-4875 4275);
DISPLAY INVISIBLE (-4875 4275);
FORCEPROP 1 LAST OFFPAGE TRUE
J 0
(-4350 4075);
DISPLAY 0.872340 (-4350 4075);
PAINT GREEN (-4350 4075);
DISPLAY INVISIBLE (-4350 4075);
FORCEADD Q_RES..1
R 1
(-9350 5850);
FORCEPROP 1 LAST LOCATION PR340
J 0
(-9325 6000);
DISPLAY 0.489362 (-9325 6000);
PAINT SKYBLUE (-9325 6000);
FORCEPROP 0 LAST $SEC 1
R 1
J 0
(-9325 6025);
DISPLAY 0.680851 (-9325 6025);
PAINT MONO (-9325 6025);
DISPLAY INVISIBLE (-9325 6025);
FORCEPROP 0 LAST CDS_SEC 1
R 1
J 0
(-9325 6025);
DISPLAY 1.021277 (-9325 6025);
DISPLAY INVISIBLE (-9325 6025);
FORCEPROP 1 LASTPIN (-9350 5750) $PN 1
R 1
J 0
(-9362 5762);
DISPLAY 0.787234 (-9362 5762);
PAINT MONO (-9362 5762);
DISPLAY INVISIBLE (-9362 5762);
FORCEPROP 1 LASTPIN (-9350 5950) $PN 2
R 1
J 0
(-9362 5912);
DISPLAY 0.787234 (-9362 5912);
PAINT MONO (-9362 5912);
DISPLAY INVISIBLE (-9362 5912);
FORCEPROP 1 LAST WATTAGE 1/16W
J 0
(-9325 5850);
DISPLAY 0.489362 (-9325 5850);
PAINT SKYBLUE (-9325 5850);
FORCEPROP 1 LAST MATERIAL CHIP
J 0
(-9325 5800);
DISPLAY 0.489362 (-9325 5800);
PAINT SKYBLUE (-9325 5800);
FORCEPROP 1 LAST TOLERANCE 5%
J 0
(-9325 5900);
DISPLAY 0.489362 (-9325 5900);
PAINT SKYBLUE (-9325 5900);
FORCEPROP 1 LAST VALUE 0
J 2
(-9300 5950);
DISPLAY 0.489362 (-9300 5950);
PAINT SKYBLUE (-9300 5950);
FORCEPROP 1 LAST PART_NUMBER CS00002JB38
J 0
(-9325 5750);
DISPLAY 0.489362 (-9325 5750);
PAINT SKYBLUE (-9325 5750);
FORCEPROP 1 LAST PACK_TYPE 0402LF
J 0
(-9325 5700);
DISPLAY 0.489362 (-9325 5700);
PAINT SKYBLUE (-9325 5700);
FORCEPROP 2 LAST CDS_LIB pure_quanta
J 0
(-9350 5850);
DISPLAY INVISIBLE (-9350 5850);
FORCEPROP 1 LAST PATH I179
R 1
J 0
(-9500 5800);
DISPLAY 0.978723 (-9500 5800);
PAINT WHITE (-9500 5800);
DISPLAY INVISIBLE (-9500 5800);
FORCEADD VCC_CORE..1
(-9350 6050);
FORCEPROP 3 LASTPIN (-9350 6000) SIG_NAME P5V_STBY\g
J 0
(-9340 6010);
DISPLAY 0.659574 (-9340 6010);
PAINT MONO (-9340 6010);
DISPLAY INVISIBLE (-9340 6010);
FORCEPROP 1 LAST HDL_POWER P5V_STBY
J 1
(-9350 6100);
DISPLAY 0.489362 (-9350 6100);
PAINT GREEN (-9350 6100);
FORCEPROP 2 LAST CDS_LIB pure_quanta_power
J 0
(-9350 6050);
DISPLAY INVISIBLE (-9350 6050);
FORCEPROP 1 LAST PATH I180
J 0
(-9300 6075);
DISPLAY 0.872340 (-9300 6075);
PAINT AQUA (-9300 6075);
DISPLAY INVISIBLE (-9300 6075);
FORCEADD Q_RES..1
R 1
(-9000 5850);
FORCEPROP 1 LAST LOCATION PR341
J 0
(-8950 6000);
DISPLAY 0.489362 (-8950 6000);
PAINT SKYBLUE (-8950 6000);
FORCEPROP 0 LAST $SEC 1
R 1
J 0
(-8950 6025);
DISPLAY 0.680851 (-8950 6025);
PAINT MONO (-8950 6025);
DISPLAY INVISIBLE (-8950 6025);
FORCEPROP 0 LAST CDS_SEC 1
R 1
J 0
(-8950 6025);
DISPLAY 1.021277 (-8950 6025);
DISPLAY INVISIBLE (-8950 6025);
FORCEPROP 1 LASTPIN (-9000 5750) $PN 1
R 1
J 0
(-9012 5762);
DISPLAY 0.787234 (-9012 5762);
PAINT MONO (-9012 5762);
DISPLAY INVISIBLE (-9012 5762);
FORCEPROP 1 LASTPIN (-9000 5950) $PN 2
R 1
J 0
(-9012 5912);
DISPLAY 0.787234 (-9012 5912);
PAINT MONO (-9012 5912);
DISPLAY INVISIBLE (-9012 5912);
FORCEPROP 1 LAST WATTAGE 1/16W
J 0
(-8950 5850);
DISPLAY 0.489362 (-8950 5850);
PAINT SKYBLUE (-8950 5850);
FORCEPROP 1 LAST MATERIAL EMPTY
J 0
(-8950 5800);
DISPLAY 0.489362 (-8950 5800);
PAINT RED (-8950 5800);
FORCEPROP 1 LAST TOLERANCE 5%
J 0
(-8950 5900);
DISPLAY 0.489362 (-8950 5900);
PAINT SKYBLUE (-8950 5900);
FORCEPROP 1 LAST VALUE 0
J 2
(-8925 5950);
DISPLAY 0.489362 (-8925 5950);
PAINT SKYBLUE (-8925 5950);
FORCEPROP 1 LAST PART_NUMBER CS00002JB38
J 0
(-8950 5750);
DISPLAY 0.489362 (-8950 5750);
PAINT SKYBLUE (-8950 5750);
FORCEPROP 1 LAST PACK_TYPE 0402LF
J 0
(-8950 5700);
DISPLAY 0.489362 (-8950 5700);
PAINT SKYBLUE (-8950 5700);
FORCEPROP 2 LAST CDS_LIB pure_quanta
J 0
(-9000 5850);
DISPLAY INVISIBLE (-9000 5850);
FORCEPROP 1 LAST PATH I181
R 1
J 0
(-9150 5800);
DISPLAY 0.978723 (-9150 5800);
PAINT WHITE (-9150 5800);
DISPLAY INVISIBLE (-9150 5800);
FORCEADD VCC_CORE..1
(-9000 6050);
FORCEPROP 3 LASTPIN (-9000 6000) SIG_NAME P3V3_STBY\g
J 0
(-8990 6010);
DISPLAY 0.659574 (-8990 6010);
PAINT MONO (-8990 6010);
DISPLAY INVISIBLE (-8990 6010);
FORCEPROP 1 LAST HDL_POWER P3V3_STBY
J 1
(-9000 6100);
DISPLAY 0.489362 (-9000 6100);
PAINT GREEN (-9000 6100);
FORCEPROP 2 LAST CDS_LIB pure_quanta_power
J 0
(-9000 6050);
DISPLAY INVISIBLE (-9000 6050);
FORCEPROP 1 LAST PATH I182
J 0
(-8950 6075);
DISPLAY 0.872340 (-8950 6075);
PAINT AQUA (-8950 6075);
DISPLAY INVISIBLE (-8950 6075);
FORCEADD VCC_CORE..1
(-8600 3200);
FORCEPROP 3 LASTPIN (-8600 3150) SIG_NAME PVDDCR_CPU1_P1_PVCC\g
J 0
(-8590 3160);
DISPLAY 0.659574 (-8590 3160);
PAINT MONO (-8590 3160);
DISPLAY INVISIBLE (-8590 3160);
FORCEPROP 1 LAST HDL_POWER PVDDCR_CPU1_P1_PVCC
J 1
(-8600 3250);
DISPLAY 0.489362 (-8600 3250);
PAINT GREEN (-8600 3250);
FORCEPROP 2 LAST CDS_LIB pure_quanta_power
J 0
(-8600 3200);
DISPLAY INVISIBLE (-8600 3200);
FORCEPROP 1 LAST PATH I183
J 0
(-8550 3225);
DISPLAY 0.872340 (-8550 3225);
PAINT AQUA (-8550 3225);
DISPLAY INVISIBLE (-8550 3225);
FORCEADD Q_RES..2
(-1025 4250);
FORCEPROP 1 LAST LOCATION PR342
J 0
(-980 4375);
DISPLAY 0.489362 (-980 4375);
PAINT SKYBLUE (-980 4375);
FORCEPROP 0 LAST $SEC 1
J 0
(-975 4400);
DISPLAY 0.680851 (-975 4400);
PAINT MONO (-975 4400);
DISPLAY INVISIBLE (-975 4400);
FORCEPROP 0 LAST CDS_SEC 1
J 0
(-975 4400);
DISPLAY 1.021277 (-975 4400);
DISPLAY INVISIBLE (-975 4400);
FORCEPROP 1 LASTPIN (-1025 4350) $PN 1
J 0
(-1020 4312);
DISPLAY 0.787234 (-1020 4312);
PAINT MONO (-1020 4312);
DISPLAY INVISIBLE (-1020 4312);
FORCEPROP 1 LASTPIN (-1025 4150) $PN 2
J 0
(-1020 4160);
DISPLAY 0.787234 (-1020 4160);
PAINT MONO (-1020 4160);
DISPLAY INVISIBLE (-1020 4160);
FORCEPROP 1 LAST WATTAGE 1/16W
J 0
(-985 4225);
DISPLAY 0.489362 (-985 4225);
PAINT SKYBLUE (-985 4225);
FORCEPROP 1 LAST MATERIAL CHIP
J 0
(-985 4175);
DISPLAY 0.489362 (-985 4175);
PAINT SKYBLUE (-985 4175);
FORCEPROP 1 LAST TOLERANCE 1%
J 0
(-980 4275);
DISPLAY 0.489362 (-980 4275);
PAINT SKYBLUE (-980 4275);
FORCEPROP 1 LAST VALUE 1K
J 0
(-980 4325);
DISPLAY 0.489362 (-980 4325);
PAINT SKYBLUE (-980 4325);
FORCEPROP 1 LAST PART_NUMBER TMP_QCS21002FB24
J 0
(-985 4125);
DISPLAY 0.489362 (-985 4125);
PAINT SKYBLUE (-985 4125);
FORCEPROP 1 LAST PACK_TYPE 0402LF
J 0
(-985 4075);
DISPLAY 0.489362 (-985 4075);
PAINT SKYBLUE (-985 4075);
FORCEPROP 2 LAST CDS_LIB pure_quanta
J 0
(-1025 4250);
DISPLAY INVISIBLE (-1025 4250);
FORCEPROP 1 LAST PATH I184
J 0
(-975 4425);
DISPLAY 0.978723 (-975 4425);
PAINT WHITE (-975 4425);
DISPLAY INVISIBLE (-975 4425);
FORCEADD VCC_CORE..1
(-4750 5750);
FORCEPROP 3 LASTPIN (-4750 5700) SIG_NAME SW_P12V_STBY_PVDDCR_CPU1_P1_FLT\g
J 0
(-4740 5710);
DISPLAY 0.659574 (-4740 5710);
PAINT MONO (-4740 5710);
DISPLAY INVISIBLE (-4740 5710);
FORCEPROP 1 LAST HDL_POWER SW_P12V_STBY_PVDDCR_CPU1_P1_FLT
J 1
(-4750 5800);
DISPLAY 0.489362 (-4750 5800);
PAINT GREEN (-4750 5800);
FORCEPROP 2 LAST CDS_LIB pure_quanta_power
J 0
(-4750 5750);
DISPLAY INVISIBLE (-4750 5750);
FORCEPROP 1 LAST PATH I185
J 0
(-4700 5775);
DISPLAY 0.872340 (-4700 5775);
PAINT AQUA (-4700 5775);
DISPLAY INVISIBLE (-4700 5775);
FORCEADD UNIVERSAL_GND..1
(-6300 1100);
FORCEPROP 3 LASTPIN (-6300 1150) SIG_NAME GND\g
J 0
(-6290 1160);
DISPLAY 0.659574 (-6290 1160);
PAINT MONO (-6290 1160);
DISPLAY INVISIBLE (-6290 1160);
FORCEPROP 2 LAST CDS_LIB pure_quanta_power
J 0
(-6300 1100);
PAINT MONO (-6300 1100);
DISPLAY INVISIBLE (-6300 1100);
FORCEPROP 1 LAST PATH I19
J 0
(-6225 1100);
DISPLAY 0.872340 (-6225 1100);
PAINT AQUA (-6225 1100);
DISPLAY INVISIBLE (-6225 1100);
FORCEPROP 1 LAST HDL_POWER GND
J 1
(-6275 1025);
DISPLAY 0.872340 (-6275 1025);
PAINT GREEN (-6275 1025);
DISPLAY INVISIBLE (-6275 1025);
FORCEADD Q_RES..2
R 2
(-8875 1325);
FORCEPROP 1 LAST LOCATION PR254
J 2
(-8920 1450);
DISPLAY 0.489362 (-8920 1450);
PAINT SKYBLUE (-8920 1450);
FORCEPROP 0 LAST $SEC 1
J 0
(-8900 1500);
DISPLAY 0.680851 (-8900 1500);
PAINT MONO (-8900 1500);
DISPLAY INVISIBLE (-8900 1500);
FORCEPROP 0 LAST CDS_SEC 1
J 0
(-8900 1500);
DISPLAY 1.021277 (-8900 1500);
DISPLAY INVISIBLE (-8900 1500);
FORCEPROP 1 LASTPIN (-8875 1425) $PN 1
J 2
(-8880 1387);
DISPLAY 0.489362 (-8880 1387);
PAINT MONO (-8880 1387);
FORCEPROP 1 LASTPIN (-8875 1225) $PN 2
J 2
(-8880 1235);
DISPLAY 0.489362 (-8880 1235);
PAINT MONO (-8880 1235);
FORCEPROP 1 LAST WATTAGE 1/16W
J 2
(-8915 1300);
DISPLAY 0.489362 (-8915 1300);
PAINT SKYBLUE (-8915 1300);
FORCEPROP 1 LAST MATERIAL EMPTY
J 2
(-8915 1250);
DISPLAY 0.489362 (-8915 1250);
PAINT RED (-8915 1250);
FORCEPROP 1 LAST TOLERANCE 1%
J 2
(-8920 1350);
DISPLAY 0.489362 (-8920 1350);
PAINT SKYBLUE (-8920 1350);
FORCEPROP 1 LAST VALUE 8.87K
J 2
(-8920 1400);
DISPLAY 0.489362 (-8920 1400);
PAINT SKYBLUE (-8920 1400);
FORCEPROP 1 LAST PART_NUMBER CS28872FB01
J 2
(-8915 1200);
DISPLAY 0.489362 (-8915 1200);
PAINT SKYBLUE (-8915 1200);
FORCEPROP 1 LAST PACK_TYPE 0402LF
J 2
(-8915 1150);
DISPLAY 0.489362 (-8915 1150);
PAINT SKYBLUE (-8915 1150);
FORCEPROP 2 LAST CDS_LIB pure_quanta
J 2
(-8875 1325);
DISPLAY INVISIBLE (-8875 1325);
FORCEPROP 1 LAST PATH I2
J 2
(-8925 1500);
DISPLAY 0.978723 (-8925 1500);
PAINT WHITE (-8925 1500);
DISPLAY INVISIBLE (-8925 1500);
FORCEADD ISL99390FRZTR5935..1
(-6925 4450);
FORCEPROP 1 LAST LOCATION PU35
J 0
(-7225 5325);
DISPLAY 0.489362 (-7225 5325);
PAINT SKYBLUE (-7225 5325);
FORCEPROP 2 LAST $SEC 1
J 0
(-7225 5500);
DISPLAY 0.680851 (-7225 5500);
PAINT MONO (-7225 5500);
DISPLAY INVISIBLE (-7225 5500);
FORCEPROP 2 LAST CDS_SEC 1
J 0
(-7225 5500);
DISPLAY 1.021277 (-7225 5500);
DISPLAY INVISIBLE (-7225 5500);
FORCEPROP 2 LASTPIN (-6525 4000) $PN 2
J 0
(-6515 4010);
DISPLAY 0.489362 (-6515 4010);
PAINT MONO (-6515 4010);
FORCEPROP 2 LASTPIN (-6525 4800) $PN 33
J 0
(-6515 4810);
DISPLAY 0.489362 (-6515 4810);
PAINT MONO (-6515 4810);
FORCEPROP 2 LASTPIN (-7375 4200) $PN 31
J 2
(-7385 4210);
DISPLAY 0.489362 (-7385 4210);
PAINT MONO (-7385 4210);
FORCEPROP 2 LASTPIN (-7375 4600) $PN 35
J 2
(-7385 4610);
DISPLAY 0.489362 (-7385 4610);
PAINT MONO (-7385 4610);
FORCEPROP 2 LASTPIN (-6525 4150) $PN 6
J 0
(-6515 4160);
DISPLAY 0.489362 (-6515 4160);
PAINT MONO (-6515 4160);
FORCEPROP 2 LASTPIN (-6525 4100) $PN 41
J 0
(-6515 4110);
DISPLAY 0.489362 (-6515 4110);
PAINT MONO (-6515 4110);
FORCEPROP 2 LASTPIN (-7375 4450) $PN 38
J 2
(-7385 4460);
DISPLAY 0.489362 (-7385 4460);
PAINT MONO (-7385 4460);
FORCEPROP 2 LASTPIN (-7375 4150) $PN 37
J 2
(-7385 4160);
DISPLAY 0.489362 (-7385 4160);
PAINT MONO (-7385 4160);
FORCEPROP 2 LASTPIN (-6525 3950) $PN 5
J 0
(-6515 3960);
DISPLAY 0.489362 (-6515 3960);
PAINT MONO (-6515 3960);
FORCEPROP 2 LASTPIN (-6525 3900) $PN 7_9-20_24
J 0
(-6515 3910);
DISPLAY 0.489362 (-6515 3910);
PAINT MONO (-6515 3910);
FORCEPROP 2 LASTPIN (-6525 3850) $PN 40
J 0
(-6515 3860);
DISPLAY 0.489362 (-6515 3860);
PAINT MONO (-6515 3860);
FORCEPROP 2 LASTPIN (-6525 4550) $PN 32
J 0
(-6515 4560);
DISPLAY 0.489362 (-6515 4560);
PAINT MONO (-6515 4560);
FORCEPROP 2 LASTPIN (-7375 5100) $PN 4
J 2
(-7385 5110);
DISPLAY 0.489362 (-7385 5110);
PAINT MONO (-7385 5110);
FORCEPROP 2 LASTPIN (-7375 3850) $PN 34
J 2
(-7385 3860);
DISPLAY 0.489362 (-7385 3860);
PAINT MONO (-7385 3860);
FORCEPROP 2 LASTPIN (-7375 4350) $PN 39
J 2
(-7385 4360);
DISPLAY 0.489362 (-7385 4360);
PAINT MONO (-7385 4360);
FORCEPROP 2 LASTPIN (-6525 4450) $PN 10_19
J 0
(-6515 4460);
DISPLAY 0.489362 (-6515 4460);
PAINT MONO (-6515 4460);
FORCEPROP 2 LASTPIN (-7375 3950) $PN 36
J 2
(-7385 3960);
DISPLAY 0.489362 (-7385 3960);
PAINT MONO (-7385 3960);
FORCEPROP 2 LASTPIN (-7375 4800) $PN 3
J 2
(-7385 4810);
DISPLAY 0.489362 (-7385 4810);
PAINT MONO (-7385 4810);
FORCEPROP 2 LASTPIN (-6525 5100) $PN 25_29
J 0
(-6515 5110);
DISPLAY 0.489362 (-6515 5110);
PAINT MONO (-6515 5110);
FORCEPROP 2 LASTPIN (-6525 5050) $PN 30
J 0
(-6515 5060);
DISPLAY 0.489362 (-6515 5060);
PAINT MONO (-6515 5060);
FORCEPROP 2 LASTPIN (-6525 4200) $PN 1
J 0
(-6515 4210);
DISPLAY 0.489362 (-6515 4210);
PAINT MONO (-6515 4210);
FORCEPROP 2 LAST PART_TYPE SMLF
J 0
(-7225 5450);
DISPLAY 0.808511 (-7225 5450);
FORCEPROP 1 LAST MATERIAL IC
J 0
(-7225 5175);
DISPLAY 0.489362 (-7225 5175);
PAINT SKYBLUE (-7225 5175);
FORCEPROP 2 LAST VALUE ISL99390FRZ-TR5935
J 0
(-7225 5400);
DISPLAY 0.489362 (-7225 5400);
PAINT SKYBLUE (-7225 5400);
FORCEPROP 1 LAST PART_NUMBER AL099390004
J 0
(-7225 5250);
DISPLAY 0.489362 (-7225 5250);
PAINT SKYBLUE (-7225 5250);
FORCEPROP 1 LAST NEEDS_NO_SIZE TRUE
J 0
(-6925 4450);
DISPLAY 0.723404 (-6925 4450);
PAINT GREEN (-6925 4450);
DISPLAY INVISIBLE (-6925 4450);
FORCEPROP 1 LAST CDS_LMAN_SYM_OUTLINE -300,700,250,-650
J 0
(-6925 4450);
DISPLAY 0.468085 (-6925 4450);
PAINT GREEN (-6925 4450);
DISPLAY INVISIBLE (-6925 4450);
FORCEPROP 2 LAST CDS_LIB pure_quanta
J 0
(-6925 4450);
DISPLAY INVISIBLE (-6925 4450);
FORCEPROP 1 LAST PATH I21
J 0
(-6925 4450);
DISPLAY 0.723404 (-6925 4450);
PAINT GREEN (-6925 4450);
DISPLAY INVISIBLE (-6925 4450);
FORCEADD Q_CAP..1
(-5725 2725);
FORCEPROP 1 LAST LOCATION PC378_2
J 0
(-5675 2875);
DISPLAY 0.489362 (-5675 2875);
PAINT SKYBLUE (-5675 2875);
FORCEPROP 0 LAST $SEC 1
J 0
(-5675 2925);
DISPLAY 0.680851 (-5675 2925);
PAINT MONO (-5675 2925);
DISPLAY INVISIBLE (-5675 2925);
FORCEPROP 0 LAST CDS_SEC 1
J 0
(-5675 2925);
DISPLAY 1.021277 (-5675 2925);
DISPLAY INVISIBLE (-5675 2925);
FORCEPROP 1 LASTPIN (-5725 2825) $PN 1
J 0
(-5715 2805);
DISPLAY 0.489362 (-5715 2805);
PAINT MONO (-5715 2805);
FORCEPROP 1 LASTPIN (-5725 2625) $PN 2
J 0
(-5715 2605);
DISPLAY 0.489362 (-5715 2605);
PAINT MONO (-5715 2605);
FORCEPROP 1 LAST MATERIAL X6S
J 0
(-5675 2675);
DISPLAY 0.489362 (-5675 2675);
PAINT SKYBLUE (-5675 2675);
FORCEPROP 1 LAST TOLERANCE 10%
J 0
(-5675 2725);
DISPLAY 0.489362 (-5675 2725);
PAINT SKYBLUE (-5675 2725);
FORCEPROP 1 LAST VALUE 1UF
J 0
(-5675 2825);
DISPLAY 0.489362 (-5675 2825);
PAINT SKYBLUE (-5675 2825);
FORCEPROP 1 LAST PART_NUMBER CH5104KEB02
J 0
(-5675 2575);
DISPLAY 0.489362 (-5675 2575);
PAINT SKYBLUE (-5675 2575);
FORCEPROP 1 LAST VOLTAGE 25V
J 0
(-5675 2775);
DISPLAY 0.489362 (-5675 2775);
PAINT SKYBLUE (-5675 2775);
FORCEPROP 1 LAST PACK_TYPE C0402
J 0
(-5675 2625);
DISPLAY 0.489362 (-5675 2625);
PAINT SKYBLUE (-5675 2625);
FORCEPROP 2 LAST CDS_LIB pure_quanta
J 0
(-5725 2725);
DISPLAY INVISIBLE (-5725 2725);
FORCEPROP 1 LAST PATH I23
J 0
(-5675 2875);
DISPLAY 0.978723 (-5675 2875);
PAINT WHITE (-5675 2875);
DISPLAY INVISIBLE (-5675 2875);
FORCEADD Q_CAP..1
(-5325 2725);
FORCEPROP 1 LAST LOCATION PC380_2
J 0
(-5275 2875);
DISPLAY 0.489362 (-5275 2875);
PAINT SKYBLUE (-5275 2875);
FORCEPROP 0 LAST $SEC 1
J 0
(-5275 2925);
DISPLAY 0.680851 (-5275 2925);
PAINT MONO (-5275 2925);
DISPLAY INVISIBLE (-5275 2925);
FORCEPROP 0 LAST CDS_SEC 1
J 0
(-5275 2925);
DISPLAY 1.021277 (-5275 2925);
DISPLAY INVISIBLE (-5275 2925);
FORCEPROP 1 LASTPIN (-5325 2825) $PN 1
J 0
(-5315 2805);
DISPLAY 0.489362 (-5315 2805);
PAINT MONO (-5315 2805);
FORCEPROP 1 LASTPIN (-5325 2625) $PN 2
J 0
(-5315 2605);
DISPLAY 0.489362 (-5315 2605);
PAINT MONO (-5315 2605);
FORCEPROP 1 LAST MATERIAL X6S
J 0
(-5275 2675);
DISPLAY 0.489362 (-5275 2675);
PAINT SKYBLUE (-5275 2675);
FORCEPROP 1 LAST TOLERANCE 10%
J 0
(-5275 2725);
DISPLAY 0.489362 (-5275 2725);
PAINT SKYBLUE (-5275 2725);
FORCEPROP 1 LAST VALUE 10UF
J 0
(-5275 2825);
DISPLAY 0.489362 (-5275 2825);
PAINT SKYBLUE (-5275 2825);
FORCEPROP 1 LAST PART_NUMBER CH6104KEA00
J 0
(-5275 2575);
DISPLAY 0.489362 (-5275 2575);
PAINT SKYBLUE (-5275 2575);
FORCEPROP 1 LAST VOLTAGE 25V
J 0
(-5275 2775);
DISPLAY 0.489362 (-5275 2775);
PAINT SKYBLUE (-5275 2775);
FORCEPROP 1 LAST PACK_TYPE C0805
J 0
(-5275 2625);
DISPLAY 0.489362 (-5275 2625);
PAINT SKYBLUE (-5275 2625);
FORCEPROP 2 LAST CDS_LIB pure_quanta
J 0
(-5325 2725);
DISPLAY INVISIBLE (-5325 2725);
FORCEPROP 1 LAST PATH I24
J 0
(-5275 2875);
DISPLAY 0.978723 (-5275 2875);
PAINT WHITE (-5275 2875);
DISPLAY INVISIBLE (-5275 2875);
FORCEADD UNIVERSAL_GND..1
(-6275 3725);
FORCEPROP 3 LASTPIN (-6275 3775) SIG_NAME GND\g
J 0
(-6265 3785);
DISPLAY 0.659574 (-6265 3785);
PAINT MONO (-6265 3785);
DISPLAY INVISIBLE (-6265 3785);
FORCEPROP 2 LAST CDS_LIB pure_quanta_power
J 0
(-6275 3725);
PAINT MONO (-6275 3725);
DISPLAY INVISIBLE (-6275 3725);
FORCEPROP 1 LAST PATH I25
J 0
(-6200 3725);
DISPLAY 0.872340 (-6200 3725);
PAINT AQUA (-6200 3725);
DISPLAY INVISIBLE (-6200 3725);
FORCEPROP 1 LAST HDL_POWER GND
J 1
(-6250 3650);
DISPLAY 0.872340 (-6250 3650);
PAINT GREEN (-6250 3650);
DISPLAY INVISIBLE (-6250 3650);
FORCEADD OFFPAGE..1
(-8275 4350);
FORCEPROP 2 LAST $XR5 199 
J 0
(-9127 4350);
DISPLAY 0.638298 (-9127 4350);
PAINT MONO (-9127 4350);
FORCEPROP 2 LAST $XR4 198 
J 0
(-9007 4350);
DISPLAY 0.638298 (-9007 4350);
PAINT MONO (-9007 4350);
FORCEPROP 2 LAST $XR3 196 
J 0
(-8887 4350);
DISPLAY 0.638298 (-8887 4350);
PAINT MONO (-8887 4350);
FORCEPROP 2 LAST $XR2 195 
J 0
(-8767 4350);
DISPLAY 0.638298 (-8767 4350);
PAINT MONO (-8767 4350);
FORCEPROP 2 LAST $XR1 194 
J 0
(-8647 4350);
DISPLAY 0.638298 (-8647 4350);
PAINT MONO (-8647 4350);
FORCEPROP 2 LAST $XR0 193 
J 0
(-8527 4350);
DISPLAY 0.638298 (-8527 4350);
PAINT MONO (-8527 4350);
FORCEPROP 1 LAST OFFPAGE TRUE
J 0
(-7950 4225);
DISPLAY 0.872340 (-7950 4225);
PAINT GREEN (-7950 4225);
DISPLAY INVISIBLE (-7950 4225);
FORCEPROP 1 LAST COMMENT_BODY TRUE
J 0
(-8150 4250);
DISPLAY 0.872340 (-8150 4250);
PAINT GREEN (-8150 4250);
DISPLAY INVISIBLE (-8150 4250);
FORCEPROP 2 LAST CDS_LIB standard
J 0
(-8275 4350);
DISPLAY INVISIBLE (-8275 4350);
FORCEPROP 2 LAST PATH I27
J 0
(-8525 4400);
DISPLAY 1.021277 (-8525 4400);
DISPLAY INVISIBLE (-8525 4400);
FORCEADD OFFPAGE..5
(-8275 4450);
FORCEPROP 2 LAST $XR0 193 
J 0
(-8560 4450);
DISPLAY 0.638298 (-8560 4450);
PAINT MONO (-8560 4450);
FORCEPROP 1 LAST OFFPAGE TRUE
J 0
(-7950 4325);
DISPLAY 0.872340 (-7950 4325);
PAINT GREEN (-7950 4325);
DISPLAY INVISIBLE (-7950 4325);
FORCEPROP 1 LAST COMMENT_BODY TRUE
J 0
(-8175 4375);
DISPLAY 0.872340 (-8175 4375);
PAINT GREEN (-8175 4375);
DISPLAY INVISIBLE (-8175 4375);
FORCEPROP 2 LAST CDS_LIB standard
J 0
(-8275 4450);
DISPLAY INVISIBLE (-8275 4450);
FORCEPROP 2 LAST PATH I28
J 0
(-8550 4500);
DISPLAY 1.021277 (-8550 4500);
DISPLAY INVISIBLE (-8550 4500);
FORCEADD OFFPAGE..1
(-8325 1225);
FORCEPROP 2 LAST $XR0 193 
J 0
(-8577 1225);
DISPLAY 0.638298 (-8577 1225);
PAINT MONO (-8577 1225);
FORCEPROP 2 LAST PATH I3
J 0
(-8575 1275);
DISPLAY 1.021277 (-8575 1275);
DISPLAY INVISIBLE (-8575 1275);
FORCEPROP 2 LAST CDS_LIB standard
J 0
(-8325 1225);
DISPLAY INVISIBLE (-8325 1225);
FORCEPROP 1 LAST COMMENT_BODY TRUE
J 0
(-8200 1125);
DISPLAY 0.872340 (-8200 1125);
PAINT GREEN (-8200 1125);
DISPLAY INVISIBLE (-8200 1125);
FORCEPROP 1 LAST OFFPAGE TRUE
J 0
(-8000 1100);
DISPLAY 0.872340 (-8000 1100);
PAINT GREEN (-8000 1100);
DISPLAY INVISIBLE (-8000 1100);
FORCEADD Q_CAP..1
(-5750 5350);
FORCEPROP 1 LAST LOCATION PC377_1
J 0
(-5700 5500);
DISPLAY 0.489362 (-5700 5500);
PAINT SKYBLUE (-5700 5500);
FORCEPROP 0 LAST $SEC 1
J 0
(-5700 5550);
DISPLAY 0.680851 (-5700 5550);
PAINT MONO (-5700 5550);
DISPLAY INVISIBLE (-5700 5550);
FORCEPROP 0 LAST CDS_SEC 1
J 0
(-5700 5550);
DISPLAY 1.021277 (-5700 5550);
DISPLAY INVISIBLE (-5700 5550);
FORCEPROP 1 LASTPIN (-5750 5450) $PN 1
J 0
(-5740 5430);
DISPLAY 0.489362 (-5740 5430);
PAINT MONO (-5740 5430);
FORCEPROP 1 LASTPIN (-5750 5250) $PN 2
J 0
(-5740 5230);
DISPLAY 0.489362 (-5740 5230);
PAINT MONO (-5740 5230);
FORCEPROP 1 LAST MATERIAL X6S
J 0
(-5700 5300);
DISPLAY 0.489362 (-5700 5300);
PAINT SKYBLUE (-5700 5300);
FORCEPROP 1 LAST TOLERANCE 10%
J 0
(-5700 5350);
DISPLAY 0.489362 (-5700 5350);
PAINT SKYBLUE (-5700 5350);
FORCEPROP 1 LAST VALUE 1UF
J 0
(-5700 5450);
DISPLAY 0.489362 (-5700 5450);
PAINT SKYBLUE (-5700 5450);
FORCEPROP 1 LAST PART_NUMBER CH5104KEB02
J 0
(-5700 5200);
DISPLAY 0.489362 (-5700 5200);
PAINT SKYBLUE (-5700 5200);
FORCEPROP 1 LAST VOLTAGE 25V
J 0
(-5700 5400);
DISPLAY 0.489362 (-5700 5400);
PAINT SKYBLUE (-5700 5400);
FORCEPROP 1 LAST PACK_TYPE C0402
J 0
(-5700 5250);
DISPLAY 0.489362 (-5700 5250);
PAINT SKYBLUE (-5700 5250);
FORCEPROP 2 LAST CDS_LIB pure_quanta
J 0
(-5750 5350);
DISPLAY INVISIBLE (-5750 5350);
FORCEPROP 1 LAST PATH I41
J 0
(-5700 5500);
DISPLAY 0.978723 (-5700 5500);
PAINT WHITE (-5700 5500);
DISPLAY INVISIBLE (-5700 5500);
FORCEADD Q_CAP..1
(-4925 2725);
FORCEPROP 1 LAST LOCATION PC382_2
J 0
(-4875 2875);
DISPLAY 0.489362 (-4875 2875);
PAINT SKYBLUE (-4875 2875);
FORCEPROP 0 LAST $SEC 1
J 0
(-4875 2925);
DISPLAY 0.680851 (-4875 2925);
PAINT MONO (-4875 2925);
DISPLAY INVISIBLE (-4875 2925);
FORCEPROP 0 LAST CDS_SEC 1
J 0
(-4875 2925);
DISPLAY 1.021277 (-4875 2925);
DISPLAY INVISIBLE (-4875 2925);
FORCEPROP 1 LASTPIN (-4925 2825) $PN 1
J 0
(-4915 2805);
DISPLAY 0.489362 (-4915 2805);
PAINT MONO (-4915 2805);
FORCEPROP 1 LASTPIN (-4925 2625) $PN 2
J 0
(-4915 2605);
DISPLAY 0.489362 (-4915 2605);
PAINT MONO (-4915 2605);
FORCEPROP 1 LAST TOLERANCE 10%
J 0
(-4875 2725);
DISPLAY 0.489362 (-4875 2725);
PAINT SKYBLUE (-4875 2725);
FORCEPROP 1 LAST VALUE 10UF
J 0
(-4875 2825);
DISPLAY 0.489362 (-4875 2825);
PAINT SKYBLUE (-4875 2825);
FORCEPROP 1 LAST VOLTAGE 25V
J 0
(-4875 2775);
DISPLAY 0.489362 (-4875 2775);
PAINT SKYBLUE (-4875 2775);
FORCEPROP 1 LAST MATERIAL X6S
J 0
(-4875 2675);
DISPLAY 0.489362 (-4875 2675);
PAINT SKYBLUE (-4875 2675);
FORCEPROP 1 LAST PACK_TYPE C0805
J 0
(-4875 2625);
DISPLAY 0.489362 (-4875 2625);
PAINT SKYBLUE (-4875 2625);
FORCEPROP 1 LAST PART_NUMBER CH6104KEA00
J 0
(-4875 2575);
DISPLAY 0.489362 (-4875 2575);
PAINT SKYBLUE (-4875 2575);
FORCEPROP 2 LAST CDS_LIB pure_quanta
J 0
(-4925 2725);
DISPLAY INVISIBLE (-4925 2725);
FORCEPROP 1 LAST PATH I46
J 0
(-4875 2875);
DISPLAY 0.978723 (-4875 2875);
PAINT WHITE (-4875 2875);
DISPLAY INVISIBLE (-4875 2875);
FORCEADD Q_CAP..1
(-4550 2725);
FORCEPROP 1 LAST LOCATION PC385_2
J 0
(-4500 2875);
DISPLAY 0.489362 (-4500 2875);
PAINT SKYBLUE (-4500 2875);
FORCEPROP 0 LAST $SEC 1
J 0
(-4500 2925);
DISPLAY 0.680851 (-4500 2925);
PAINT MONO (-4500 2925);
DISPLAY INVISIBLE (-4500 2925);
FORCEPROP 0 LAST CDS_SEC 1
J 0
(-4500 2925);
DISPLAY 1.021277 (-4500 2925);
DISPLAY INVISIBLE (-4500 2925);
FORCEPROP 1 LASTPIN (-4550 2825) $PN 1
J 0
(-4540 2805);
DISPLAY 0.489362 (-4540 2805);
PAINT MONO (-4540 2805);
FORCEPROP 1 LASTPIN (-4550 2625) $PN 2
J 0
(-4540 2605);
DISPLAY 0.489362 (-4540 2605);
PAINT MONO (-4540 2605);
FORCEPROP 1 LAST MATERIAL X6S
J 0
(-4500 2675);
DISPLAY 0.489362 (-4500 2675);
PAINT SKYBLUE (-4500 2675);
FORCEPROP 1 LAST TOLERANCE 10%
J 0
(-4500 2725);
DISPLAY 0.489362 (-4500 2725);
PAINT SKYBLUE (-4500 2725);
FORCEPROP 1 LAST VALUE 10UF
J 0
(-4500 2825);
DISPLAY 0.489362 (-4500 2825);
PAINT SKYBLUE (-4500 2825);
FORCEPROP 1 LAST PART_NUMBER CH6104KEA00
J 0
(-4500 2575);
DISPLAY 0.489362 (-4500 2575);
PAINT SKYBLUE (-4500 2575);
FORCEPROP 1 LAST VOLTAGE 25V
J 0
(-4500 2775);
DISPLAY 0.489362 (-4500 2775);
PAINT SKYBLUE (-4500 2775);
FORCEPROP 1 LAST PACK_TYPE C0805
J 0
(-4500 2625);
DISPLAY 0.489362 (-4500 2625);
PAINT SKYBLUE (-4500 2625);
FORCEPROP 2 LAST CDS_LIB pure_quanta
J 0
(-4550 2725);
DISPLAY INVISIBLE (-4550 2725);
FORCEPROP 1 LAST PATH I47
J 0
(-4500 2875);
DISPLAY 0.978723 (-4500 2875);
PAINT WHITE (-4500 2875);
DISPLAY INVISIBLE (-4500 2875);
FORCEADD UNIVERSAL_GND..1
(-4550 2350);
FORCEPROP 3 LASTPIN (-4550 2400) SIG_NAME GND\g
J 0
(-4540 2410);
DISPLAY 0.659574 (-4540 2410);
PAINT MONO (-4540 2410);
DISPLAY INVISIBLE (-4540 2410);
FORCEPROP 2 LAST CDS_LIB pure_quanta_power
J 0
(-4550 2350);
PAINT MONO (-4550 2350);
DISPLAY INVISIBLE (-4550 2350);
FORCEPROP 1 LAST PATH I48
J 0
(-4475 2350);
DISPLAY 0.872340 (-4475 2350);
PAINT AQUA (-4475 2350);
DISPLAY INVISIBLE (-4475 2350);
FORCEPROP 1 LAST HDL_POWER GND
J 1
(-4525 2275);
DISPLAY 0.872340 (-4525 2275);
PAINT GREEN (-4525 2275);
DISPLAY INVISIBLE (-4525 2275);
FORCEADD VCC_CORE..1
(-4550 3075);
FORCEPROP 3 LASTPIN (-4550 3025) SIG_NAME SW_P12V_STBY_PVDDCR_CPU1_P1_FLT\g
J 0
(-4540 3035);
DISPLAY 0.659574 (-4540 3035);
PAINT MONO (-4540 3035);
DISPLAY INVISIBLE (-4540 3035);
FORCEPROP 1 LAST HDL_POWER SW_P12V_STBY_PVDDCR_CPU1_P1_FLT
J 1
(-4550 3125);
DISPLAY 0.489362 (-4550 3125);
PAINT GREEN (-4550 3125);
FORCEPROP 2 LAST CDS_LIB pure_quanta_power
J 0
(-4550 3075);
DISPLAY INVISIBLE (-4550 3075);
FORCEPROP 1 LAST PATH I49
J 0
(-4500 3100);
DISPLAY 0.872340 (-4500 3100);
PAINT AQUA (-4500 3100);
DISPLAY INVISIBLE (-4500 3100);
FORCEADD OFFPAGE..5
(-8325 1325);
FORCEPROP 2 LAST $XR3 193 
J 0
(-8700 1289);
DISPLAY 0.638298 (-8700 1289);
PAINT MONO (-8700 1289);
FORCEPROP 2 LAST $XR2 196 
J 0
(-8580 1289);
DISPLAY 0.638298 (-8580 1289);
PAINT MONO (-8580 1289);
FORCEPROP 2 LAST $XR1 195 
J 0
(-8700 1325);
DISPLAY 0.638298 (-8700 1325);
PAINT MONO (-8700 1325);
FORCEPROP 2 LAST $XR0 194 
J 0
(-8580 1325);
DISPLAY 0.638298 (-8580 1325);
PAINT MONO (-8580 1325);
FORCEPROP 1 LAST COMMENT_BODY TRUE
J 0
(-8225 1250);
DISPLAY 0.872340 (-8225 1250);
PAINT GREEN (-8225 1250);
DISPLAY INVISIBLE (-8225 1250);
FORCEPROP 2 LAST CDS_LIB standard
J 0
(-8325 1325);
DISPLAY INVISIBLE (-8325 1325);
FORCEPROP 2 LAST PATH I5
J 0
(-8575 1400);
DISPLAY 1.021277 (-8575 1400);
DISPLAY INVISIBLE (-8575 1400);
FORCEPROP 1 LAST OFFPAGE TRUE
J 0
(-8000 1200);
DISPLAY 0.872340 (-8000 1200);
PAINT GREEN (-8000 1200);
DISPLAY INVISIBLE (-8000 1200);
FORCEADD OFFPAGE..1
(-8325 1725);
FORCEPROP 2 LAST $XR5 199 
J 0
(-9177 1725);
DISPLAY 0.638298 (-9177 1725);
PAINT MONO (-9177 1725);
FORCEPROP 2 LAST $XR4 198 
J 0
(-9057 1725);
DISPLAY 0.638298 (-9057 1725);
PAINT MONO (-9057 1725);
FORCEPROP 2 LAST $XR3 196 
J 0
(-8937 1725);
DISPLAY 0.638298 (-8937 1725);
PAINT MONO (-8937 1725);
FORCEPROP 2 LAST $XR2 195 
J 0
(-8817 1725);
DISPLAY 0.638298 (-8817 1725);
PAINT MONO (-8817 1725);
FORCEPROP 2 LAST $XR1 194 
J 0
(-8697 1725);
DISPLAY 0.638298 (-8697 1725);
PAINT MONO (-8697 1725);
FORCEPROP 2 LAST $XR0 193 
J 0
(-8577 1725);
DISPLAY 0.638298 (-8577 1725);
PAINT MONO (-8577 1725);
FORCEPROP 2 LAST PATH I6
J 0
(-8575 1775);
DISPLAY 1.021277 (-8575 1775);
DISPLAY INVISIBLE (-8575 1775);
FORCEPROP 2 LAST CDS_LIB standard
J 0
(-8325 1725);
DISPLAY INVISIBLE (-8325 1725);
FORCEPROP 1 LAST COMMENT_BODY TRUE
J 0
(-8200 1625);
DISPLAY 0.872340 (-8200 1625);
PAINT GREEN (-8200 1625);
DISPLAY INVISIBLE (-8200 1625);
FORCEPROP 1 LAST OFFPAGE TRUE
J 0
(-8000 1600);
DISPLAY 0.872340 (-8000 1600);
PAINT GREEN (-8000 1600);
DISPLAY INVISIBLE (-8000 1600);
FORCEADD UNIVERSAL_GND..1
(-4700 4950);
FORCEPROP 3 LASTPIN (-4700 5000) SIG_NAME GND\g
J 0
(-4690 5010);
DISPLAY 0.659574 (-4690 5010);
PAINT MONO (-4690 5010);
DISPLAY INVISIBLE (-4690 5010);
FORCEPROP 2 LAST CDS_LIB pure_quanta_power
J 0
(-4700 4950);
PAINT MONO (-4700 4950);
DISPLAY INVISIBLE (-4700 4950);
FORCEPROP 1 LAST PATH I64
J 0
(-4625 4950);
DISPLAY 0.872340 (-4625 4950);
PAINT AQUA (-4625 4950);
DISPLAY INVISIBLE (-4625 4950);
FORCEPROP 1 LAST HDL_POWER GND
J 1
(-4675 4875);
DISPLAY 0.872340 (-4675 4875);
PAINT GREEN (-4675 4875);
DISPLAY INVISIBLE (-4675 4875);
FORCEADD Q_CAP..1
(-5350 5350);
FORCEPROP 1 LAST LOCATION PC379_1
J 0
(-5300 5500);
DISPLAY 0.489362 (-5300 5500);
PAINT SKYBLUE (-5300 5500);
FORCEPROP 0 LAST $SEC 1
J 0
(-5300 5550);
DISPLAY 0.680851 (-5300 5550);
PAINT MONO (-5300 5550);
DISPLAY INVISIBLE (-5300 5550);
FORCEPROP 0 LAST CDS_SEC 1
J 0
(-5300 5550);
DISPLAY 1.021277 (-5300 5550);
DISPLAY INVISIBLE (-5300 5550);
FORCEPROP 1 LASTPIN (-5350 5450) $PN 1
J 0
(-5340 5430);
DISPLAY 0.489362 (-5340 5430);
PAINT MONO (-5340 5430);
FORCEPROP 1 LASTPIN (-5350 5250) $PN 2
J 0
(-5340 5230);
DISPLAY 0.489362 (-5340 5230);
PAINT MONO (-5340 5230);
FORCEPROP 1 LAST TOLERANCE 10%
J 0
(-5300 5350);
DISPLAY 0.489362 (-5300 5350);
PAINT SKYBLUE (-5300 5350);
FORCEPROP 1 LAST VOLTAGE 25V
J 0
(-5300 5400);
DISPLAY 0.489362 (-5300 5400);
PAINT SKYBLUE (-5300 5400);
FORCEPROP 1 LAST MATERIAL X6S
J 0
(-5300 5300);
DISPLAY 0.489362 (-5300 5300);
PAINT SKYBLUE (-5300 5300);
FORCEPROP 1 LAST PACK_TYPE C0805
J 0
(-5300 5250);
DISPLAY 0.489362 (-5300 5250);
PAINT SKYBLUE (-5300 5250);
FORCEPROP 1 LAST PART_NUMBER CH6104KEA00
J 0
(-5300 5200);
DISPLAY 0.489362 (-5300 5200);
PAINT SKYBLUE (-5300 5200);
FORCEPROP 1 LAST VALUE 10UF
J 0
(-5300 5450);
DISPLAY 0.489362 (-5300 5450);
PAINT SKYBLUE (-5300 5450);
FORCEPROP 2 LAST CDS_LIB pure_quanta
J 0
(-5350 5350);
DISPLAY INVISIBLE (-5350 5350);
FORCEPROP 1 LAST PATH I65
J 0
(-5300 5500);
DISPLAY 0.978723 (-5300 5500);
PAINT WHITE (-5300 5500);
DISPLAY INVISIBLE (-5300 5500);
FORCEADD Q_CAP..1
(-4950 5350);
FORCEPROP 1 LAST LOCATION PC381_1
J 0
(-4900 5500);
DISPLAY 0.489362 (-4900 5500);
PAINT SKYBLUE (-4900 5500);
FORCEPROP 0 LAST $SEC 1
J 0
(-4900 5550);
DISPLAY 0.680851 (-4900 5550);
PAINT MONO (-4900 5550);
DISPLAY INVISIBLE (-4900 5550);
FORCEPROP 0 LAST CDS_SEC 1
J 0
(-4900 5550);
DISPLAY 1.021277 (-4900 5550);
DISPLAY INVISIBLE (-4900 5550);
FORCEPROP 1 LASTPIN (-4950 5450) $PN 1
J 0
(-4940 5430);
DISPLAY 0.489362 (-4940 5430);
PAINT MONO (-4940 5430);
FORCEPROP 1 LASTPIN (-4950 5250) $PN 2
J 0
(-4940 5230);
DISPLAY 0.489362 (-4940 5230);
PAINT MONO (-4940 5230);
FORCEPROP 1 LAST VALUE 10UF
J 0
(-4900 5450);
DISPLAY 0.489362 (-4900 5450);
PAINT SKYBLUE (-4900 5450);
FORCEPROP 1 LAST MATERIAL X6S
J 0
(-4900 5300);
DISPLAY 0.489362 (-4900 5300);
PAINT SKYBLUE (-4900 5300);
FORCEPROP 1 LAST TOLERANCE 10%
J 0
(-4900 5350);
DISPLAY 0.489362 (-4900 5350);
PAINT SKYBLUE (-4900 5350);
FORCEPROP 1 LAST VOLTAGE 25V
J 0
(-4900 5400);
DISPLAY 0.489362 (-4900 5400);
PAINT SKYBLUE (-4900 5400);
FORCEPROP 1 LAST PACK_TYPE C0805
J 0
(-4900 5250);
DISPLAY 0.489362 (-4900 5250);
PAINT SKYBLUE (-4900 5250);
FORCEPROP 1 LAST PART_NUMBER CH6104KEA00
J 0
(-4900 5200);
DISPLAY 0.489362 (-4900 5200);
PAINT SKYBLUE (-4900 5200);
FORCEPROP 2 LAST CDS_LIB pure_quanta
J 0
(-4950 5350);
DISPLAY INVISIBLE (-4950 5350);
FORCEPROP 1 LAST PATH I66
J 0
(-4900 5500);
DISPLAY 0.978723 (-4900 5500);
PAINT WHITE (-4900 5500);
DISPLAY INVISIBLE (-4900 5500);
FORCEADD Q_CAP..1
(-4575 5350);
FORCEPROP 1 LAST LOCATION PC384_1
J 0
(-4525 5500);
DISPLAY 0.489362 (-4525 5500);
PAINT SKYBLUE (-4525 5500);
FORCEPROP 0 LAST $SEC 1
J 0
(-4525 5550);
DISPLAY 0.680851 (-4525 5550);
PAINT MONO (-4525 5550);
DISPLAY INVISIBLE (-4525 5550);
FORCEPROP 0 LAST CDS_SEC 1
J 0
(-4525 5550);
DISPLAY 1.021277 (-4525 5550);
DISPLAY INVISIBLE (-4525 5550);
FORCEPROP 1 LASTPIN (-4575 5450) $PN 1
J 0
(-4565 5430);
DISPLAY 0.489362 (-4565 5430);
PAINT MONO (-4565 5430);
FORCEPROP 1 LASTPIN (-4575 5250) $PN 2
J 0
(-4565 5230);
DISPLAY 0.489362 (-4565 5230);
PAINT MONO (-4565 5230);
FORCEPROP 1 LAST PART_NUMBER CH6104KEA00
J 0
(-4525 5200);
DISPLAY 0.489362 (-4525 5200);
PAINT SKYBLUE (-4525 5200);
FORCEPROP 1 LAST PACK_TYPE C0805
J 0
(-4525 5250);
DISPLAY 0.489362 (-4525 5250);
PAINT SKYBLUE (-4525 5250);
FORCEPROP 1 LAST VOLTAGE 25V
J 0
(-4525 5400);
DISPLAY 0.489362 (-4525 5400);
PAINT SKYBLUE (-4525 5400);
FORCEPROP 1 LAST MATERIAL X6S
J 0
(-4525 5300);
DISPLAY 0.489362 (-4525 5300);
PAINT SKYBLUE (-4525 5300);
FORCEPROP 1 LAST TOLERANCE 10%
J 0
(-4525 5350);
DISPLAY 0.489362 (-4525 5350);
PAINT SKYBLUE (-4525 5350);
FORCEPROP 1 LAST VALUE 10UF
J 0
(-4525 5450);
DISPLAY 0.489362 (-4525 5450);
PAINT SKYBLUE (-4525 5450);
FORCEPROP 2 LAST CDS_LIB pure_quanta
J 0
(-4575 5350);
DISPLAY INVISIBLE (-4575 5350);
FORCEPROP 1 LAST PATH I67
J 0
(-4525 5500);
DISPLAY 0.978723 (-4525 5500);
PAINT WHITE (-4525 5500);
DISPLAY INVISIBLE (-4525 5500);
FORCEADD VCC_CORE..1
(-3200 5725);
FORCEPROP 3 LASTPIN (-3200 5675) SIG_NAME P12V_STBY\g
J 0
(-3190 5685);
DISPLAY 0.659574 (-3190 5685);
PAINT MONO (-3190 5685);
DISPLAY INVISIBLE (-3190 5685);
FORCEPROP 1 LAST HDL_POWER P12V_STBY
J 1
(-3200 5775);
DISPLAY 0.489362 (-3200 5775);
PAINT GREEN (-3200 5775);
FORCEPROP 2 LAST CDS_LIB pure_quanta_power
J 0
(-3200 5725);
DISPLAY INVISIBLE (-3200 5725);
FORCEPROP 1 LAST PATH I73
J 0
(-3150 5750);
DISPLAY 0.872340 (-3150 5750);
PAINT AQUA (-3150 5750);
DISPLAY INVISIBLE (-3150 5750);
FORCEADD Q_CAPP..1
(-4250 5350);
FORCEPROP 1 LAST LOCATION PC390
J 0
(-4200 5475);
DISPLAY 0.489362 (-4200 5475);
PAINT SKYBLUE (-4200 5475);
FORCEPROP 0 LAST $SEC 1
J 0
(-4200 5525);
DISPLAY 0.680851 (-4200 5525);
PAINT MONO (-4200 5525);
DISPLAY INVISIBLE (-4200 5525);
FORCEPROP 0 LAST CDS_SEC 1
J 0
(-4200 5525);
DISPLAY 1.021277 (-4200 5525);
DISPLAY INVISIBLE (-4200 5525);
FORCEPROP 1 LASTPIN (-4250 5450) $PN 1
J 0
(-4240 5435);
DISPLAY 0.489362 (-4240 5435);
PAINT MONO (-4240 5435);
FORCEPROP 1 LASTPIN (-4250 5250) $PN 2
J 0
(-4240 5235);
DISPLAY 0.489362 (-4240 5235);
PAINT MONO (-4240 5235);
FORCEPROP 1 LAST PART_NUMBER CC72204MD02
J 0
(-4200 5175);
DISPLAY 0.489362 (-4200 5175);
PAINT SKYBLUE (-4200 5175);
FORCEPROP 1 LAST MATERIAL OSCON
J 0
(-4200 5275);
DISPLAY 0.489362 (-4200 5275);
PAINT SKYBLUE (-4200 5275);
FORCEPROP 1 LAST VOLTAGE 25V
J 0
(-4200 5325);
DISPLAY 0.489362 (-4200 5325);
PAINT SKYBLUE (-4200 5325);
FORCEPROP 1 LAST TOLERANCE 20%
J 0
(-4200 5375);
DISPLAY 0.489362 (-4200 5375);
PAINT SKYBLUE (-4200 5375);
FORCEPROP 1 LAST VALUE 220UF
J 0
(-4200 5425);
DISPLAY 0.489362 (-4200 5425);
PAINT SKYBLUE (-4200 5425);
FORCEPROP 1 LAST PACK_TYPE THLF
J 0
(-4200 5225);
DISPLAY 0.489362 (-4200 5225);
PAINT SKYBLUE (-4200 5225);
FORCEPROP 2 LAST CDS_LIB pure_quanta
J 0
(-4250 5350);
DISPLAY INVISIBLE (-4250 5350);
FORCEPROP 1 LAST PATH I74
J 0
(-4200 5500);
DISPLAY 0.978723 (-4200 5500);
DISPLAY INVISIBLE (-4200 5500);
FORCEADD Q_INDUCTOR..1
(-3475 5625);
FORCEPROP 1 LAST LOCATION PL42
J 0
(-3600 5775);
DISPLAY 0.489362 (-3600 5775);
PAINT SKYBLUE (-3600 5775);
FORCEPROP 2 LAST $SEC 1
J 0
(-3600 5900);
DISPLAY 0.680851 (-3600 5900);
PAINT MONO (-3600 5900);
DISPLAY INVISIBLE (-3600 5900);
FORCEPROP 0 LAST CDS_SEC 1
J 0
(-3500 5725);
DISPLAY 1.021277 (-3500 5725);
DISPLAY INVISIBLE (-3500 5725);
FORCEPROP 2 LASTPIN (-3575 5600) $PN 1
J 2
(-3585 5610);
DISPLAY 0.489362 (-3585 5610);
FORCEPROP 2 LASTPIN (-3375 5600) $PN 2
J 0
(-3365 5610);
DISPLAY 0.489362 (-3365 5610);
FORCEPROP 1 LAST MATERIAL IND
J 0
(-3600 5680);
DISPLAY 0.489362 (-3600 5680);
PAINT SKYBLUE (-3600 5680);
FORCEPROP 2 LAST VALUE 50NH/86A
J 0
(-3600 5825);
DISPLAY 0.489362 (-3600 5825);
PAINT SKYBLUE (-3600 5825);
FORCEPROP 1 LAST PART_NUMBER CVA50^0MZ09
J 0
(-3600 5735);
DISPLAY 0.489362 (-3600 5735);
PAINT SKYBLUE (-3600 5735);
FORCEPROP 2 LAST PACK_TYPE SMLF
J 0
(-3600 5875);
DISPLAY 0.489362 (-3600 5875);
PAINT SKYBLUE (-3600 5875);
FORCEPROP 1 LAST NEEDS_NO_SIZE TRUE
J 0
(-3475 5625);
DISPLAY 0.468085 (-3475 5625);
PAINT GREEN (-3475 5625);
DISPLAY INVISIBLE (-3475 5625);
FORCEPROP 2 LAST CDS_LIB pure_quanta
J 0
(-3475 5625);
PAINT MONO (-3475 5625);
DISPLAY INVISIBLE (-3475 5625);
FORCEPROP 1 LAST PATH I75
J 0
(-3400 5680);
DISPLAY 0.723404 (-3400 5680);
PAINT GREEN (-3400 5680);
DISPLAY INVISIBLE (-3400 5680);
FORCEADD Q_CAPP..1
(-3850 5350);
FORCEPROP 1 LAST LOCATION PC393
J 0
(-3800 5475);
DISPLAY 0.489362 (-3800 5475);
PAINT SKYBLUE (-3800 5475);
FORCEPROP 0 LAST $SEC 1
J 0
(-3800 5525);
DISPLAY 0.680851 (-3800 5525);
PAINT MONO (-3800 5525);
DISPLAY INVISIBLE (-3800 5525);
FORCEPROP 0 LAST CDS_SEC 1
J 0
(-3800 5525);
DISPLAY 1.021277 (-3800 5525);
DISPLAY INVISIBLE (-3800 5525);
FORCEPROP 1 LASTPIN (-3850 5450) $PN 1
J 0
(-3840 5435);
DISPLAY 0.489362 (-3840 5435);
PAINT MONO (-3840 5435);
FORCEPROP 1 LASTPIN (-3850 5250) $PN 2
J 0
(-3840 5235);
DISPLAY 0.489362 (-3840 5235);
PAINT MONO (-3840 5235);
FORCEPROP 1 LAST PART_NUMBER CC72204MD02
J 0
(-3800 5175);
DISPLAY 0.489362 (-3800 5175);
PAINT SKYBLUE (-3800 5175);
FORCEPROP 1 LAST MATERIAL OSCON
J 0
(-3800 5275);
DISPLAY 0.489362 (-3800 5275);
PAINT SKYBLUE (-3800 5275);
FORCEPROP 1 LAST TOLERANCE 20%
J 0
(-3800 5375);
DISPLAY 0.489362 (-3800 5375);
PAINT SKYBLUE (-3800 5375);
FORCEPROP 1 LAST VALUE 220UF
J 0
(-3800 5425);
DISPLAY 0.489362 (-3800 5425);
PAINT SKYBLUE (-3800 5425);
FORCEPROP 1 LAST VOLTAGE 25V
J 0
(-3800 5325);
DISPLAY 0.489362 (-3800 5325);
PAINT SKYBLUE (-3800 5325);
FORCEPROP 1 LAST PACK_TYPE THLF
J 0
(-3800 5225);
DISPLAY 0.489362 (-3800 5225);
PAINT SKYBLUE (-3800 5225);
FORCEPROP 2 LAST CDS_LIB pure_quanta
J 0
(-3850 5350);
DISPLAY INVISIBLE (-3850 5350);
FORCEPROP 1 LAST PATH I76
J 0
(-3800 5500);
DISPLAY 0.978723 (-3800 5500);
DISPLAY INVISIBLE (-3800 5500);
FORCEADD ISL99390FRZTR5935..1
(-6950 1825);
FORCEPROP 1 LAST LOCATION PU5
J 0
(-7250 2700);
DISPLAY 0.489362 (-7250 2700);
PAINT SKYBLUE (-7250 2700);
FORCEPROP 2 LAST SEC 1
J 0
(-7250 2875);
DISPLAY 0.680851 (-7250 2875);
PAINT MONO (-7250 2875);
DISPLAY INVISIBLE (-7250 2875);
FORCEPROP 2 LASTPIN (-6550 1375) $PN 2
J 0
(-6540 1385);
DISPLAY 0.489362 (-6540 1385);
PAINT MONO (-6540 1385);
FORCEPROP 2 LASTPIN (-6550 2175) $PN 33
J 0
(-6540 2185);
DISPLAY 0.489362 (-6540 2185);
PAINT MONO (-6540 2185);
FORCEPROP 2 LASTPIN (-7400 1575) $PN 31
J 2
(-7410 1585);
DISPLAY 0.489362 (-7410 1585);
PAINT MONO (-7410 1585);
FORCEPROP 2 LASTPIN (-7400 1975) $PN 35
J 2
(-7410 1985);
DISPLAY 0.489362 (-7410 1985);
PAINT MONO (-7410 1985);
FORCEPROP 2 LASTPIN (-6550 1525) $PN 6
J 0
(-6540 1535);
DISPLAY 0.489362 (-6540 1535);
PAINT MONO (-6540 1535);
FORCEPROP 2 LASTPIN (-6550 1475) $PN 41
J 0
(-6540 1485);
DISPLAY 0.489362 (-6540 1485);
PAINT MONO (-6540 1485);
FORCEPROP 2 LASTPIN (-7400 1825) $PN 38
J 2
(-7410 1835);
DISPLAY 0.489362 (-7410 1835);
PAINT MONO (-7410 1835);
FORCEPROP 2 LASTPIN (-7400 1525) $PN 37
J 2
(-7410 1535);
DISPLAY 0.489362 (-7410 1535);
PAINT MONO (-7410 1535);
FORCEPROP 2 LASTPIN (-6550 1325) $PN 5
J 0
(-6540 1335);
DISPLAY 0.489362 (-6540 1335);
PAINT MONO (-6540 1335);
FORCEPROP 2 LASTPIN (-6550 1275) $PN 7_9-20_24
J 0
(-6540 1285);
DISPLAY 0.489362 (-6540 1285);
PAINT MONO (-6540 1285);
FORCEPROP 2 LASTPIN (-6550 1225) $PN 40
J 0
(-6540 1235);
DISPLAY 0.489362 (-6540 1235);
PAINT MONO (-6540 1235);
FORCEPROP 2 LASTPIN (-6550 1925) $PN 32
J 0
(-6540 1935);
DISPLAY 0.489362 (-6540 1935);
PAINT MONO (-6540 1935);
FORCEPROP 2 LASTPIN (-7400 2475) $PN 4
J 2
(-7410 2485);
DISPLAY 0.489362 (-7410 2485);
PAINT MONO (-7410 2485);
FORCEPROP 2 LASTPIN (-7400 1225) $PN 34
J 2
(-7410 1235);
DISPLAY 0.489362 (-7410 1235);
PAINT MONO (-7410 1235);
FORCEPROP 2 LASTPIN (-7400 1725) $PN 39
J 2
(-7410 1735);
DISPLAY 0.489362 (-7410 1735);
PAINT MONO (-7410 1735);
FORCEPROP 2 LASTPIN (-6550 1825) $PN 10_19
J 0
(-6540 1835);
DISPLAY 0.489362 (-6540 1835);
PAINT MONO (-6540 1835);
FORCEPROP 2 LASTPIN (-7400 1325) $PN 36
J 2
(-7410 1335);
DISPLAY 0.489362 (-7410 1335);
PAINT MONO (-7410 1335);
FORCEPROP 2 LASTPIN (-7400 2175) $PN 3
J 2
(-7410 2185);
DISPLAY 0.489362 (-7410 2185);
PAINT MONO (-7410 2185);
FORCEPROP 2 LASTPIN (-6550 2475) $PN 25_29
J 0
(-6540 2485);
DISPLAY 0.489362 (-6540 2485);
PAINT MONO (-6540 2485);
FORCEPROP 2 LASTPIN (-6550 2425) $PN 30
J 0
(-6540 2435);
DISPLAY 0.489362 (-6540 2435);
PAINT MONO (-6540 2435);
FORCEPROP 2 LASTPIN (-6550 1575) $PN 1
J 0
(-6540 1585);
DISPLAY 0.489362 (-6540 1585);
PAINT MONO (-6540 1585);
FORCEPROP 2 LAST PART_TYPE SMLF
J 0
(-7250 2825);
DISPLAY 0.808511 (-7250 2825);
FORCEPROP 2 LAST VALUE ISL99390FRZ-TR5935
J 0
(-7250 2775);
DISPLAY 0.489362 (-7250 2775);
PAINT SKYBLUE (-7250 2775);
FORCEPROP 1 LAST PART_NUMBER AL099390004
J 0
(-7250 2625);
DISPLAY 0.489362 (-7250 2625);
PAINT SKYBLUE (-7250 2625);
FORCEPROP 1 LAST MATERIAL IC
J 0
(-7250 2550);
DISPLAY 0.489362 (-7250 2550);
PAINT SKYBLUE (-7250 2550);
FORCEPROP 2 LAST SEC_TYPE 
J 0
(-7250 2875);
DISPLAY 1.021277 (-7250 2875);
DISPLAY INVISIBLE (-7250 2875);
FORCEPROP 2 LAST CDS_LIB pure_quanta
J 0
(-6950 1825);
DISPLAY INVISIBLE (-6950 1825);
FORCEPROP 1 LAST CDS_LMAN_SYM_OUTLINE -300,700,250,-650
J 0
(-6950 1825);
DISPLAY 0.468085 (-6950 1825);
PAINT GREEN (-6950 1825);
DISPLAY INVISIBLE (-6950 1825);
FORCEPROP 1 LAST NEEDS_NO_SIZE TRUE
J 0
(-6950 1825);
DISPLAY 0.723404 (-6950 1825);
PAINT GREEN (-6950 1825);
DISPLAY INVISIBLE (-6950 1825);
FORCEPROP 1 LAST PATH I87
J 0
(-6950 1825);
DISPLAY 0.723404 (-6950 1825);
PAINT GREEN (-6950 1825);
DISPLAY INVISIBLE (-6950 1825);
FORCEADD DNS..1
(-8850 3925);
PAINT RED (-8850 3925);
FORCEPROP 2 LAST CDS_LIB mstr_misc
J 0
(-8850 3925);
PAINT MONO (-8850 3925);
DISPLAY INVISIBLE (-8850 3925);
FORCEPROP 1 LAST COMMENT_BODY TRUE
R 1
J 0
(-8775 3700);
DISPLAY 0.872340 (-8775 3700);
PAINT GREEN (-8775 3700);
DISPLAY INVISIBLE (-8775 3700);
FORCEADD DNS..1
(-5475 3725);
PAINT RED (-5475 3725);
FORCEPROP 2 LAST CDS_LIB mstr_misc
J 0
(-5475 3725);
DISPLAY INVISIBLE (-5475 3725);
FORCEPROP 1 LAST COMMENT_BODY TRUE
R 1
J 0
(-5400 3500);
DISPLAY 0.872340 (-5400 3500);
PAINT GREEN (-5400 3500);
DISPLAY INVISIBLE (-5400 3500);
FORCEADD DNS..1
(-5475 4250);
PAINT RED (-5475 4250);
FORCEPROP 2 LAST CDS_LIB mstr_misc
J 0
(-5475 4250);
DISPLAY INVISIBLE (-5475 4250);
FORCEPROP 1 LAST COMMENT_BODY TRUE
R 1
J 0
(-5400 4025);
DISPLAY 0.872340 (-5400 4025);
PAINT GREEN (-5400 4025);
DISPLAY INVISIBLE (-5400 4025);
FORCEADD DNS..1
(-8975 5850);
PAINT RED (-8975 5850);
FORCEPROP 2 LAST CDS_LIB mstr_misc
J 0
(-8975 5850);
DISPLAY INVISIBLE (-8975 5850);
FORCEPROP 1 LAST COMMENT_BODY TRUE
R 1
J 0
(-8900 5625);
DISPLAY 0.872340 (-8900 5625);
PAINT GREEN (-8900 5625);
DISPLAY INVISIBLE (-8900 5625);
FORCEADD DNS..1
(-8875 1300);
PAINT RED (-8875 1300);
FORCEPROP 2 LAST CDS_LIB mstr_misc
J 0
(-8875 1300);
PAINT MONO (-8875 1300);
DISPLAY INVISIBLE (-8875 1300);
FORCEPROP 1 LAST COMMENT_BODY TRUE
R 1
J 0
(-8800 1075);
DISPLAY 0.872340 (-8800 1075);
PAINT GREEN (-8800 1075);
DISPLAY INVISIBLE (-8800 1075);
FORCEADD DNS..1
(-5525 1100);
PAINT RED (-5525 1100);
FORCEPROP 2 LAST CDS_LIB mstr_misc
J 0
(-5525 1100);
DISPLAY INVISIBLE (-5525 1100);
FORCEPROP 1 LAST COMMENT_BODY TRUE
R 1
J 0
(-5450 875);
DISPLAY 0.872340 (-5450 875);
PAINT GREEN (-5450 875);
DISPLAY INVISIBLE (-5450 875);
FORCEADD QUANTA_TITLE_BLOCK_C..1
(-550 -250);
FORCEPROP 0 LAST CDS_CON_LAST_MODIFIED Fri Mar 11 14:53:35 2022
J 0
(-2435 -235);
DISPLAY INVISIBLE (-2435 -235);
FORCEPROP 1 LAST CUSTOM_TXT_CDS <CON_LAST_MODIFIED>
J 0
(-2435 -235);
DISPLAY 0.978723 (-2435 -235);
FORCEPROP 2 LAST CUSTOM_TXT_CDS <XR_PAGE_TITLE>
J 0
(-8440 5000);
DISPLAY 0.638298 (-8440 5000);
PAINT PINK (-8440 5000);
DISPLAY INVISIBLE (-8440 5000);
FORCEPROP 1 LAST CUSTOM_TXT_CDS <NAME_2>
J 0
(-3725 -200);
FORCEPROP 1 LAST CUSTOM_TXT_CDS <NAME_1>
J 0
(-3725 -75);
FORCEPROP 1 LAST CUSTOM_TXT_CDS <Q_NUMBER>
J 0
(-1953 -147);
DISPLAY 1.212766 (-1953 -147);
FORCEPROP 1 LAST CUSTOM_TXT_CDS <Q_PROJ>
J 0
(-2932 -148);
DISPLAY 1.212766 (-2932 -148);
FORCEPROP 1 LAST CUSTOM_TXT_CDS <Q_REV>
J 0
(-734 -147);
DISPLAY 1.212766 (-734 -147);
FORCEPROP 1 LAST CUSTOM_TXT_CDS <CON_PAGE_NUM> OF <CON_TOTAL_PAGES>
J 0
(-996 -232);
DISPLAY 0.978723 (-996 -232);
FORCEPROP 1 LAST Q_DEPT BU9
J 1
(-4313 -201);
DISPLAY 1.957447 (-4313 -201);
PAINT GREEN (-4313 -201);
FORCEPROP 1 LAST Q_TITLE PVDDCR_CPU1_P1 VR PHASE 1&2
J 0
(-9825 -200);
DISPLAY 2.446809 (-9825 -200);
PAINT GREEN (-9825 -200);
FORCEPROP 2 LAST PAGE_BORDER TRUE
J 0
(-8440 5000);
DISPLAY 0.638298 (-8440 5000);
PAINT PINK (-8440 5000);
DISPLAY INVISIBLE (-8440 5000);
FORCEPROP 2 LAST CDS_LIB pure_quanta
J 0
(-550 -250);
DISPLAY INVISIBLE (-550 -250);
FORCEPROP 1 LAST CDS_LMAN_SYM_OUTLINE -9475,6775,100,-125
J 0
(-550 -250);
DISPLAY 0.468085 (-550 -250);
PAINT GREEN (-550 -250);
DISPLAY INVISIBLE (-550 -250);
FORCEPROP 1 LAST COMMENT_BODY TRUE
J 0
(-538 -263);
DISPLAY 0.978723 (-538 -263);
PAINT GREEN (-538 -263);
DISPLAY INVISIBLE (-538 -263);
FORCEPROP 2 LAST CDS_XR_PAGE_TITLE CR-194 : @T6G_MB_LIB.T6G(SCH_1):PAGE194
J 0
(-8440 5000);
DISPLAY 0.638298 (-8440 5000);
PAINT PINK (-8440 5000);
DISPLAY INVISIBLE (-8440 5000);
FORCEADD DNS..1
(-5525 1650);
PAINT RED (-5525 1650);
FORCEPROP 2 LAST CDS_LIB mstr_misc
J 0
(-5525 1650);
DISPLAY INVISIBLE (-5525 1650);
FORCEPROP 1 LAST COMMENT_BODY TRUE
R 1
J 0
(-5450 1425);
DISPLAY 0.872340 (-5450 1425);
PAINT GREEN (-5450 1425);
DISPLAY INVISIBLE (-5450 1425);
WIRE 16 -1 (-8875 1225)(-8875 1150);
WIRE 16 -1 (-8850 3850)(-8850 3775);
WIRE 16 -1 (-8700 4800)(-8700 4750);
WIRE 16 -1 (-8350 5375)(-8350 5250);
WIRE 16 -1 (-8600 2150)(-8600 2100);
WIRE 16 -1 (-8250 2725)(-8250 2600);
WIRE 16 -1 (-9350 3925)(-9350 3975);
WIRE 16 -1 (-9375 1300)(-9375 1350);
WIRE 16 -1 (-5450 3625)(-5450 3550);
WIRE 16 -1 (-5500 1000)(-5500 925);
WIRE 16 -1 (-9350 6000)(-9350 5950);
WIRE 16 -1 (-9000 6000)(-9000 5950);
WIRE 16 -1 (-3200 5600)(-3200 5675);
WIRE 16 -1 (-3375 5600)(-3200 5600);
WIRE 17 273 (-1225 2275)(-1225 3300);
WIRE 17 273 (-3125 2275)(-1225 2275);
WIRE 17 273 (-1225 3300)(-3125 3300);
WIRE 17 273 (-3125 3300)(-3125 2275);
WIRE 16 -1 (-1625 2875)(-1625 2975);
WIRE 16 -1 (-1625 3025)(-1625 2975);
WIRE 16 -1 (-1625 2975)(-1925 2975);
WIRE 16 -1 (-1925 2875)(-1925 2975);
WIRE 16 -1 (-2250 2975)(-1925 2975);
WIRE 16 -1 (-2250 2875)(-2250 2975);
WIRE 16 -1 (-2575 2975)(-2250 2975);
WIRE 16 -1 (-2575 2875)(-2575 2975);
WIRE 16 -1 (-2925 2975)(-2575 2975);
WIRE 16 -1 (-2925 2875)(-2925 2975);
WIRE 16 -1 (-2925 2675)(-2925 2525);
WIRE 16 -1 (-2925 2525)(-2575 2525);
WIRE 16 -1 (-2575 2525)(-2250 2525);
WIRE 16 -1 (-2575 2675)(-2575 2525);
WIRE 16 -1 (-2250 2525)(-1925 2525);
WIRE 16 -1 (-2250 2675)(-2250 2525);
WIRE 16 -1 (-1925 2525)(-1925 2675);
WIRE 16 -1 (-1625 2525)(-1925 2525);
WIRE 16 -1 (-1625 2675)(-1625 2525);
WIRE 16 -1 (-1625 2450)(-1625 2525);
WIRE 16 -1 (-7375 3950)(-8225 3950);
FORCEPROP 2 LAST SIG_NAME PVDDCR_CPU1_P1_TEMP0
J 0
(-8185 3960);
DISPLAY 0.489362 (-8185 3960);
WIRE 16 -1 (-2300 4450)(-2300 3425);
WIRE 16 -1 (-2150 4450)(-2300 4450);
WIRE 16 -1 (-2300 4450)(-3175 4450);
WIRE 16 -1 (-2300 3425)(-3800 3425);
WIRE 16 -1 (-2150 4350)(-2150 4450);
WIRE 16 -1 (-2150 4450)(-1800 4450);
WIRE 16 -1 (-1375 4450)(-1800 4450);
WIRE 16 -1 (-1800 4450)(-1800 4350);
WIRE 16 -1 (-1025 4450)(-1375 4450);
WIRE 16 -1 (-1375 4350)(-1375 4450);
WIRE 16 -1 (-1025 4550)(-1025 4450);
WIRE 16 -1 (-1025 4450)(-1025 4350);
WIRE 16 -1 (-4000 3425)(-5850 3425);
FORCEPROP 2 LAST SIG_NAME PVDDCR_CPU1_P1_VOS1
J 0
(-6460 4225);
DISPLAY 0.489362 (-6460 4225);
FORCEPROP 2 LASTPROP $XRERR UNIQUE?
J 0
(-6700 4225);
DISPLAY 0.638298 (-6700 4225);
PAINT MONO (-6700 4225);
DISPLAY INVISIBLE (-6700 4225);
WIRE 16 -1 (-5850 4200)(-5850 3425);
WIRE 16 -1 (-6525 4200)(-5850 4200);
WIRE 16 -1 (-6525 4000)(-6275 4000);
WIRE 16 -1 (-6275 4000)(-6275 3950);
WIRE 16 -1 (-6525 3950)(-6275 3950);
WIRE 16 -1 (-6275 3950)(-6275 3900);
WIRE 16 -1 (-6275 3900)(-6275 3850);
WIRE 16 -1 (-6525 3900)(-6275 3900);
WIRE 16 -1 (-6275 3850)(-6275 3775);
WIRE 16 -1 (-6525 3850)(-6275 3850);
WIRE 16 -1 (-8700 5075)(-8125 5075);
WIRE 16 -1 (-8700 5350)(-8700 5075);
WIRE 16 -1 (-8700 5075)(-8700 5000);
WIRE 16 -1 (-8125 5075)(-8125 4800);
WIRE 16 -1 (-7475 4800)(-8125 4800);
FORCEPROP 2 LAST SIG_NAME PVDDCR_CPU1_P1_VCC1
J 0
(-8010 4810);
DISPLAY 0.489362 (-8010 4810);
FORCEPROP 2 LASTPROP $XRERR UNIQUE?
J 0
(-8250 4810);
DISPLAY 0.638298 (-8250 4810);
PAINT MONO (-8250 4810);
DISPLAY INVISIBLE (-8250 4810);
WIRE 16 -1 (-7475 4800)(-7375 4800);
WIRE 16 -1 (-7475 4600)(-7475 4800);
WIRE 16 -1 (-7375 4600)(-7475 4600);
WIRE 16 -1 (-6550 1925)(-4475 1925);
FORCEPROP 2 LAST SIG_NAME SW_PVDDCR_CPU1_P1_BOOTR2
J 0
(-6360 1935);
DISPLAY 0.489362 (-6360 1935);
FORCEPROP 2 LASTPROP $XRERR UNIQUE?
J 0
(-6600 1935);
DISPLAY 0.638298 (-6600 1935);
PAINT MONO (-6600 1935);
DISPLAY INVISIBLE (-6600 1935);
WIRE 16 -1 (-4475 1925)(-4475 1950);
WIRE 16 -1 (-6550 1825)(-5500 1825);
FORCEPROP 2 LAST SIG_NAME SW_PVDDCR_CPU1_P1_SW2
J 0
(-6360 1835);
DISPLAY 0.489362 (-6360 1835);
FORCEPROP 2 LASTPROP $XRERR UNIQUE?
J 0
(-6600 1835);
DISPLAY 0.638298 (-6600 1835);
PAINT MONO (-6600 1835);
DISPLAY INVISIBLE (-6600 1835);
WIRE 16 -1 (-5500 1825)(-3575 1825);
WIRE 16 -1 (-5500 1825)(-5500 1750);
WIRE 16 -1 (-4175 1575)(-3575 1575);
FORCEPROP 2 LAST SIG_NAME IND_CPU1_P1_CPL1
J 0
(-4110 1585);
DISPLAY 0.489362 (-4110 1585);
WIRE 16 -1 (-5575 4800)(-4600 4800);
FORCEPROP 2 LAST SIG_NAME SW_PVDDCR_CPU1_P1_BOOT1_R
J 0
(-5360 4810);
DISPLAY 0.489362 (-5360 4810);
FORCEPROP 2 LASTPROP $XRERR UNIQUE?
J 0
(-5600 4810);
DISPLAY 0.638298 (-5600 4810);
PAINT MONO (-5600 4810);
DISPLAY INVISIBLE (-5600 4810);
WIRE 16 -1 (-4600 4800)(-4600 4775);
WIRE 16 -1 (-6525 4100)(-6000 4100);
FORCEPROP 2 LAST SIG_NAME NC_PVDDCR_CPU1_P1_GL2_1
J 0
(-6460 4110);
DISPLAY 0.489362 (-6460 4110);
FORCEPROP 2 LASTPROP $XRERR UNIQUE?
J 0
(-5970 4100);
DISPLAY 0.638298 (-5970 4100);
PAINT MONO (-5970 4100);
DISPLAY INVISIBLE (-5970 4100);
WIRE 16 -1 (-9350 5750)(-9350 5675);
WIRE 16 -1 (-9350 5675)(-9000 5675);
WIRE 16 -1 (-9000 5675)(-8700 5675);
WIRE 16 -1 (-9000 5750)(-9000 5675);
WIRE 16 -1 (-8500 5675)(-8700 5675);
WIRE 16 -1 (-8700 5550)(-8700 5675);
WIRE 16 -1 (-8500 5675)(-8350 5675);
WIRE 16 -1 (-8500 6000)(-8500 5675);
WIRE 16 -1 (-8350 5575)(-8350 5675);
WIRE 16 -1 (-7450 5675)(-8350 5675);
WIRE 16 -1 (-7450 5100)(-7450 5675);
WIRE 16 -1 (-7375 5100)(-7450 5100);
WIRE 16 -1 (-8850 4150)(-7375 4150);
FORCEPROP 2 LAST SIG_NAME PVDDCR_CPU1_P1_LSET1
J 0
(-8185 4160);
DISPLAY 0.489362 (-8185 4160);
FORCEPROP 2 LASTPROP $XRERR UNIQUE?
J 0
(-8425 4160);
DISPLAY 0.638298 (-8425 4160);
PAINT MONO (-8425 4160);
DISPLAY INVISIBLE (-8425 4160);
WIRE 16 -1 (-8850 4150)(-8850 4050);
WIRE 16 -1 (-8875 1525)(-7400 1525);
FORCEPROP 2 LAST SIG_NAME PVDDCR_CPU1_P1_LSET2
J 0
(-8235 1535);
DISPLAY 0.489362 (-8235 1535);
FORCEPROP 2 LASTPROP $XRERR UNIQUE?
J 0
(-8475 1535);
DISPLAY 0.638298 (-8475 1535);
PAINT MONO (-8475 1535);
DISPLAY INVISIBLE (-8475 1535);
WIRE 16 -1 (-8875 1525)(-8875 1425);
WIRE 16 -1 (-8600 2425)(-8025 2425);
WIRE 16 -1 (-8600 2700)(-8600 2425);
WIRE 16 -1 (-8600 2425)(-8600 2350);
WIRE 16 -1 (-8025 2175)(-8025 2425);
WIRE 16 -1 (-7500 2175)(-8025 2175);
FORCEPROP 2 LAST SIG_NAME PVDDCR_CPU1_P1_VCC2
J 0
(-7985 2185);
DISPLAY 0.489362 (-7985 2185);
FORCEPROP 2 LASTPROP $XRERR UNIQUE?
J 0
(-8225 2185);
DISPLAY 0.638298 (-8225 2185);
PAINT MONO (-8225 2185);
DISPLAY INVISIBLE (-8225 2185);
WIRE 16 -1 (-7400 2175)(-7500 2175);
WIRE 16 -1 (-7500 1975)(-7500 2175);
WIRE 16 -1 (-7400 1975)(-7500 1975);
WIRE 16 -1 (-7400 1825)(-8275 1825);
FORCEPROP 2 LAST SIG_NAME PVDDCR_CPU1_P1_IMON2
J 0
(-8235 1835);
DISPLAY 0.489362 (-8235 1835);
WIRE 16 -1 (-7375 3850)(-8225 3850);
FORCEPROP 2 LAST SIG_NAME PVDDCR_CPU1_P1_PWM1
J 0
(-8185 3860);
DISPLAY 0.489362 (-8185 3860);
WIRE 16 -1 (-7400 1225)(-8275 1225);
FORCEPROP 2 LAST SIG_NAME PVDDCR_CPU1_P1_PWM2
J 0
(-8235 1235);
DISPLAY 0.489362 (-8235 1235);
WIRE 16 -1 (-7400 1325)(-8275 1325);
FORCEPROP 2 LAST SIG_NAME PVDDCR_CPU1_P1_TEMP0
J 0
(-8235 1335);
DISPLAY 0.489362 (-8235 1335);
WIRE 16 -1 (-7400 1575)(-7775 1575);
FORCEPROP 2 LAST SIG_NAME NC_PVDDCR_CPU1_P1_DNC2
J 0
(-7970 1585);
DISPLAY 0.489362 (-7970 1585);
FORCEPROP 2 LASTPROP $XRERR UNIQUE?
J 0
(-8015 1575);
DISPLAY 0.638298 (-8015 1575);
PAINT MONO (-8015 1575);
DISPLAY INVISIBLE (-8015 1575);
WIRE 16 -1 (-6550 1375)(-6300 1375);
WIRE 16 -1 (-6300 1375)(-6300 1325);
WIRE 16 -1 (-6550 1325)(-6300 1325);
WIRE 16 -1 (-6300 1325)(-6300 1275);
WIRE 16 -1 (-6300 1275)(-6300 1225);
WIRE 16 -1 (-6550 1275)(-6300 1275);
WIRE 16 -1 (-6300 1225)(-6300 1150);
WIRE 16 -1 (-6550 1225)(-6300 1225);
WIRE 16 -1 (-6550 2425)(-6375 2425);
WIRE 16 -1 (-6375 2425)(-6375 2475);
WIRE 16 -1 (-6550 2475)(-6375 2475);
WIRE 16 -1 (-6375 2975)(-6375 2475);
WIRE 16 -1 (-6375 2975)(-6125 2975);
WIRE 16 -1 (-6125 2975)(-5725 2975);
WIRE 16 -1 (-6125 2825)(-6125 2975);
WIRE 16 -1 (-5725 2975)(-5325 2975);
WIRE 16 -1 (-5725 2825)(-5725 2975);
WIRE 16 -1 (-5325 2975)(-4925 2975);
WIRE 16 -1 (-5325 2975)(-5325 2825);
WIRE 16 -1 (-4925 2975)(-4550 2975);
WIRE 16 -1 (-4925 2825)(-4925 2975);
WIRE 16 -1 (-4550 3025)(-4550 2975);
WIRE 16 -1 (-4550 2825)(-4550 2975);
WIRE 16 -1 (-6550 2175)(-5725 2175);
FORCEPROP 2 LAST SIG_NAME SW_PVDDCR_CPU1_P1_BOOT2
J 0
(-6410 2185);
DISPLAY 0.489362 (-6410 2185);
FORCEPROP 2 LASTPROP $XRERR UNIQUE?
J 0
(-6650 2185);
DISPLAY 0.638298 (-6650 2185);
PAINT MONO (-6650 2185);
DISPLAY INVISIBLE (-6650 2185);
WIRE 16 -1 (-6550 1525)(-6025 1525);
FORCEPROP 2 LAST SIG_NAME NC_PVDDCR_CPU1_P1_GL1_2
J 0
(-6485 1535);
DISPLAY 0.489362 (-6485 1535);
FORCEPROP 2 LASTPROP $XRERR UNIQUE?
J 0
(-5995 1525);
DISPLAY 0.638298 (-5995 1525);
PAINT MONO (-5995 1525);
DISPLAY INVISIBLE (-5995 1525);
WIRE 16 -1 (-6025 1475)(-6550 1475);
FORCEPROP 2 LAST SIG_NAME NC_PVDDCR_CPU1_P1_GL2_2
J 0
(-6485 1485);
DISPLAY 0.489362 (-6485 1485);
FORCEPROP 2 LASTPROP $XRERR UNIQUE?
J 0
(-5995 1475);
DISPLAY 0.638298 (-5995 1475);
PAINT MONO (-5995 1475);
DISPLAY INVISIBLE (-5995 1475);
WIRE 16 -1 (-6550 1575)(-5875 1575);
FORCEPROP 2 LAST SIG_NAME PVDDCR_CPU1_P1_VOS2
J 0
(-6485 1600);
DISPLAY 0.489362 (-6485 1600);
FORCEPROP 2 LASTPROP $XRERR UNIQUE?
J 0
(-6725 1600);
DISPLAY 0.638298 (-6725 1600);
PAINT MONO (-6725 1600);
DISPLAY INVISIBLE (-6725 1600);
WIRE 16 -1 (-5875 1575)(-5875 600);
WIRE 16 -1 (-5875 600)(-4725 600);
WIRE 16 -1 (-5500 1550)(-5500 1200);
FORCEPROP 2 LAST SIG_NAME SW_PVDDCR_CPU1_P1_SW2_RC
J 0
(-5460 1335);
DISPLAY 0.489362 (-5460 1335);
FORCEPROP 2 LASTPROP $XRERR UNIQUE?
J 0
(-5700 1335);
DISPLAY 0.638298 (-5700 1335);
PAINT MONO (-5700 1335);
DISPLAY INVISIBLE (-5700 1335);
WIRE 16 -1 (-5450 4150)(-5450 3825);
FORCEPROP 2 LAST SIG_NAME SW_PVDDCR_CPU1_P1_SW1_RC
J 0
(-5410 3960);
DISPLAY 0.489362 (-5410 3960);
FORCEPROP 2 LASTPROP $XRERR UNIQUE?
J 0
(-5650 3960);
DISPLAY 0.638298 (-5650 3960);
PAINT MONO (-5650 3960);
DISPLAY INVISIBLE (-5650 3960);
WIRE 16 -1 (-7375 4200)(-7750 4200);
FORCEPROP 2 LAST SIG_NAME NC_PVDDCR_CPU1_P1_DNC1
J 0
(-7945 4210);
DISPLAY 0.489362 (-7945 4210);
FORCEPROP 2 LASTPROP $XRERR UNIQUE?
J 0
(-7990 4200);
DISPLAY 0.638298 (-7990 4200);
PAINT MONO (-7990 4200);
DISPLAY INVISIBLE (-7990 4200);
WIRE 16 -1 (-6525 5050)(-6350 5050);
WIRE 16 -1 (-6350 5050)(-6350 5100);
WIRE 16 -1 (-6525 5100)(-6350 5100);
WIRE 16 -1 (-6350 5600)(-6350 5100);
WIRE 16 -1 (-6350 5600)(-6150 5600);
WIRE 16 -1 (-6150 5600)(-5750 5600);
WIRE 16 -1 (-6150 5450)(-6150 5600);
WIRE 16 -1 (-5350 5600)(-5750 5600);
WIRE 16 -1 (-5750 5450)(-5750 5600);
WIRE 16 -1 (-4950 5600)(-5350 5600);
WIRE 16 -1 (-5350 5600)(-5350 5450);
WIRE 16 -1 (-4950 5600)(-4750 5600);
WIRE 16 -1 (-4950 5450)(-4950 5600);
WIRE 16 -1 (-4750 5600)(-4575 5600);
WIRE 16 -1 (-4750 5700)(-4750 5600);
WIRE 16 -1 (-4575 5600)(-4250 5600);
WIRE 16 -1 (-4575 5450)(-4575 5600);
WIRE 16 -1 (-4250 5600)(-3850 5600);
WIRE 16 -1 (-4250 5600)(-4250 5450);
WIRE 16 -1 (-3850 5600)(-3575 5600);
WIRE 16 -1 (-3850 5450)(-3850 5600);
WIRE 16 -1 (-6525 4150)(-6000 4150);
FORCEPROP 2 LAST SIG_NAME NC_PVDDCR_CPU1_P1_GL1_1
J 0
(-6460 4160);
DISPLAY 0.489362 (-6460 4160);
FORCEPROP 2 LASTPROP $XRERR UNIQUE?
J 0
(-5970 4150);
DISPLAY 0.638298 (-5970 4150);
PAINT MONO (-5970 4150);
DISPLAY INVISIBLE (-5970 4150);
WIRE 16 -1 (-6525 4800)(-5775 4800);
FORCEPROP 2 LAST SIG_NAME SW_PVDDCR_CPU1_P1_BOOT1
J 0
(-6360 4810);
DISPLAY 0.489362 (-6360 4810);
FORCEPROP 2 LASTPROP $XRERR UNIQUE?
J 0
(-6600 4810);
DISPLAY 0.638298 (-6600 4810);
PAINT MONO (-6600 4810);
DISPLAY INVISIBLE (-6600 4810);
WIRE 16 -1 (-4625 4200)(-3975 4200);
FORCEPROP 2 LAST SIG_NAME IND_CPU1_P1_CPL5
J 0
(-4485 4210);
DISPLAY 0.489362 (-4485 4210);
WIRE 16 -1 (-2775 1575)(-2400 1575);
FORCEPROP 2 LAST SIG_NAME IND_CPU1_P1_CPL2
J 0
(-2760 1585);
DISPLAY 0.489362 (-2760 1585);
WIRE 16 -1 (-4525 600)(-2000 600);
WIRE 16 -1 (-2000 1825)(-2000 600);
WIRE 16 -1 (-2775 1825)(-2000 1825);
WIRE 16 -1 (-1775 1825)(-2000 1825);
WIRE 16 -1 (-1775 1825)(-1350 1825);
WIRE 16 -1 (-1775 1825)(-1775 1725);
WIRE 16 -1 (-1350 1875)(-1350 1825);
WIRE 16 -1 (-1350 1825)(-1350 1725);
WIRE 16 -1 (-1350 1400)(-1775 1400);
WIRE 16 -1 (-1350 1400)(-1350 1525);
WIRE 16 -1 (-1350 1350)(-1350 1400);
WIRE 16 -1 (-1775 1400)(-1775 1525);
WIRE 16 -1 (-2150 4150)(-2150 4025);
WIRE 16 -1 (-2150 4025)(-1800 4025);
WIRE 16 -1 (-1800 4025)(-1800 4150);
WIRE 16 -1 (-1375 4025)(-1800 4025);
WIRE 16 -1 (-1375 4150)(-1375 4025);
WIRE 16 -1 (-1025 4025)(-1375 4025);
WIRE 16 -1 (-1025 4150)(-1025 4025);
WIRE 16 -1 (-1025 3925)(-1025 4025);
WIRE 16 -1 (-3175 4200)(-2700 4200);
FORCEPROP 2 LAST SIG_NAME IND_CPU1_P1_CPL1
J 0
(-3085 4210);
DISPLAY 0.489362 (-3085 4210);
WIRE 16 -1 (-4550 2400)(-4550 2475);
WIRE 16 -1 (-4550 2625)(-4550 2475);
WIRE 16 -1 (-4925 2475)(-4550 2475);
WIRE 16 -1 (-4925 2625)(-4925 2475);
WIRE 16 -1 (-5325 2475)(-4925 2475);
WIRE 16 -1 (-5325 2625)(-5325 2475);
WIRE 16 -1 (-5325 2475)(-5725 2475);
WIRE 16 -1 (-5725 2625)(-5725 2475);
WIRE 16 -1 (-6125 2475)(-5725 2475);
WIRE 16 -1 (-6125 2625)(-6125 2475);
WIRE 16 -1 (-5525 2175)(-4475 2175);
FORCEPROP 2 LAST SIG_NAME SW_PVDDCR_CPU1_P1_BOOT2_R
J 0
(-5235 2185);
DISPLAY 0.489362 (-5235 2185);
FORCEPROP 2 LASTPROP $XRERR UNIQUE?
J 0
(-5475 2185);
DISPLAY 0.638298 (-5475 2185);
PAINT MONO (-5475 2185);
DISPLAY INVISIBLE (-5475 2185);
WIRE 16 -1 (-4475 2175)(-4475 2150);
WIRE 16 -1 (-6525 4550)(-4600 4550);
FORCEPROP 2 LAST SIG_NAME SW_PVDDCR_CPU1_P1_BOOTR1
J 0
(-6335 4560);
DISPLAY 0.489362 (-6335 4560);
FORCEPROP 2 LASTPROP $XRERR UNIQUE?
J 0
(-6575 4560);
DISPLAY 0.638298 (-6575 4560);
PAINT MONO (-6575 4560);
DISPLAY INVISIBLE (-6575 4560);
WIRE 16 -1 (-4600 4550)(-4600 4575);
WIRE 16 -1 (-6525 4450)(-5450 4450);
FORCEPROP 2 LAST SIG_NAME SW_PVDDCR_CPU1_P1_SW1
J 0
(-6335 4460);
DISPLAY 0.489362 (-6335 4460);
FORCEPROP 2 LASTPROP $XRERR UNIQUE?
J 0
(-6575 4460);
DISPLAY 0.638298 (-6575 4460);
PAINT MONO (-6575 4460);
DISPLAY INVISIBLE (-6575 4460);
WIRE 16 -1 (-5450 4450)(-3975 4450);
WIRE 16 -1 (-5450 4350)(-5450 4450);
WIRE 16 -1 (-3850 5250)(-3850 5100);
WIRE 16 -1 (-4250 5100)(-3850 5100);
WIRE 16 -1 (-4250 5250)(-4250 5100);
WIRE 16 -1 (-4575 5100)(-4250 5100);
WIRE 16 -1 (-4575 5250)(-4575 5100);
WIRE 16 -1 (-4700 5100)(-4575 5100);
WIRE 16 -1 (-4700 5000)(-4700 5100);
WIRE 16 -1 (-4700 5100)(-4950 5100);
WIRE 16 -1 (-4950 5250)(-4950 5100);
WIRE 16 -1 (-4950 5100)(-5350 5100);
WIRE 16 -1 (-5350 5250)(-5350 5100);
WIRE 16 -1 (-5350 5100)(-5750 5100);
WIRE 16 -1 (-5750 5250)(-5750 5100);
WIRE 16 -1 (-6150 5100)(-5750 5100);
WIRE 16 -1 (-6150 5250)(-6150 5100);
WIRE 16 -1 (-7475 4275)(-9350 4275);
WIRE 16 -1 (-7475 4350)(-7475 4275);
FORCEPROP 0 LAST CDS_PHYS_NET_NAME PVCCIN_CPU0_VREF
J 0
(-7475 4300);
PAINT MONO (-7475 4300);
DISPLAY INVISIBLE (-7475 4300);
WIRE 16 -1 (-9350 4275)(-9350 4175);
WIRE 16 -1 (-8225 4350)(-7475 4350);
FORCEPROP 2 LAST SIG_NAME PVDDCR_CPU1_P1_VCCS
J 0
(-8185 4360);
DISPLAY 0.489362 (-8185 4360);
WIRE 16 -1 (-7475 4350)(-7375 4350);
WIRE 16 -1 (-7375 4450)(-8225 4450);
FORCEPROP 2 LAST SIG_NAME PVDDCR_CPU1_P1_IMON1
J 0
(-8185 4460);
DISPLAY 0.489362 (-8185 4460);
WIRE 16 -1 (-8600 2900)(-8600 3025);
WIRE 16 -1 (-8600 3150)(-8600 3025);
WIRE 16 -1 (-8250 3025)(-8600 3025);
WIRE 16 -1 (-7925 3025)(-8250 3025);
WIRE 16 -1 (-8250 2925)(-8250 3025);
WIRE 16 -1 (-7925 2475)(-7925 3025);
WIRE 16 -1 (-7400 2475)(-7925 2475);
WIRE 16 -1 (-7500 1650)(-9375 1650);
WIRE 16 -1 (-7500 1725)(-7500 1650);
FORCEPROP 0 LAST CDS_PHYS_NET_NAME PVCCIN_CPU0_VREF
J 0
(-7500 1675);
PAINT MONO (-7500 1675);
DISPLAY INVISIBLE (-7500 1675);
WIRE 16 -1 (-9375 1650)(-9375 1550);
WIRE 16 -1 (-8275 1725)(-7500 1725);
FORCEPROP 2 LAST SIG_NAME PVDDCR_CPU1_P1_VCCS
J 0
(-8235 1735);
DISPLAY 0.489362 (-8235 1735);
WIRE 16 -1 (-7500 1725)(-7400 1725);
DOT 1 (-4950 5100);
DOT 1 (-5750 5100);
DOT 1 (-8700 5075);
DOT 1 (-9000 5675);
DOT 1 (-8700 5675);
DOT 1 (-8500 5675);
DOT 1 (-8350 5675);
DOT 1 (-6275 3850);
DOT 1 (-6275 3950);
DOT 1 (-6275 3900);
DOT 1 (-7475 4350);
DOT 1 (-7475 4800);
DOT 1 (-6350 5100);
DOT 1 (-6150 5600);
DOT 1 (-5450 4450);
DOT 1 (-5350 5100);
DOT 1 (-5750 5600);
DOT 1 (-5350 5600);
DOT 1 (-4700 5100);
DOT 1 (-4575 5100);
DOT 1 (-4250 5100);
DOT 1 (-4950 5600);
DOT 1 (-4750 5600);
DOT 1 (-4575 5600);
DOT 1 (-4250 5600);
DOT 1 (-1800 4025);
DOT 1 (-1375 4025);
DOT 1 (-1025 4025);
DOT 1 (-3850 5600);
DOT 1 (-2300 4450);
DOT 1 (-2150 4450);
DOT 1 (-1800 4450);
DOT 1 (-1375 4450);
DOT 1 (-1025 4450);
DOT 1 (-1350 1825);
DOT 1 (-1350 1400);
DOT 1 (-1775 1825);
DOT 1 (-2000 1825);
DOT 1 (-4550 2975);
DOT 1 (-4550 2475);
DOT 1 (-4925 2975);
DOT 1 (-5325 2975);
DOT 1 (-5325 2475);
DOT 1 (-5725 2975);
DOT 1 (-5725 2475);
DOT 1 (-5500 1825);
DOT 1 (-6375 2475);
DOT 1 (-6300 1325);
DOT 1 (-6300 1275);
DOT 1 (-7500 2175);
DOT 1 (-7500 1725);
DOT 1 (-8250 3025);
DOT 1 (-8600 2425);
DOT 1 (-4925 2475);
DOT 1 (-1625 2975);
DOT 1 (-1925 2975);
DOT 1 (-1625 2525);
DOT 1 (-1925 2525);
DOT 1 (-2575 2975);
DOT 1 (-2575 2525);
DOT 1 (-6300 1225);
DOT 1 (-6125 2975);
DOT 1 (-2250 2525);
DOT 1 (-2250 2975);
DOT 1 (-8600 3025);
FORCENOTE
PVDDCR_CPU1_P1_PHASE2
(-7325 3000) 0;
DISPLAY LEFT (-7325 3000);
DISPLAY 1.021277 (-7325 3000);
PAINT WHITE (-7325 3000);
FORCENOTE
PU35,PU5,PU37,PU36,PU38,PU33=AL099390004/ISL99390FRZ-TR5935
(-9775 850) 0;
DISPLAY LEFT (-9775 850);
DISPLAY 1.021277 (-9775 850);
PAINT WHITE (-9775 850);
FORCENOTE
PU35,PU5,PU37,PU36,PU38,PU33 = AL021590000/TDA21590
(-9775 625) 0;
DISPLAY LEFT (-9775 625);
DISPLAY 1.021277 (-9775 625);
PAINT WHITE (-9775 625);
FORCENOTE
3RD=CC72204MD03
(-4200 4825) 0;
DISPLAY LEFT (-4200 4825);
DISPLAY 0.638298 (-4200 4825);
PAINT WHITE (-4200 4825);
FORCENOTE
2ND=CC72204MD01
(-4200 4875) 0;
DISPLAY LEFT (-4200 4875);
DISPLAY 0.638298 (-4200 4875);
PAINT WHITE (-4200 4875);
FORCENOTE
IRIPPLE:4.65A
(-4200 4975) 0;
DISPLAY LEFT (-4200 4975);
DISPLAY 0.638298 (-4200 4975);
PAINT WHITE (-4200 4975);
FORCENOTE
8*11.5
(-4200 4925) 0;
DISPLAY LEFT (-4200 4925);
DISPLAY 0.638298 (-4200 4925);
PAINT WHITE (-4200 4925);
FORCENOTE
ESR=16M OHM
(-4200 5025) 0;
DISPLAY LEFT (-4200 5025);
DISPLAY 0.638298 (-4200 5025);
PAINT WHITE (-4200 5025);
FORCENOTE
BOM NOTE
(-9775 1050) 0;
DISPLAY LEFT (-9775 1050);
DISPLAY 1.021277 (-9775 1050);
PAINT WHITE (-9775 1050);
FORCENOTE
MAIN SOURCE:RENESAS BOM
(-9775 925) 0;
DISPLAY LEFT (-9775 925);
DISPLAY 1.021277 (-9775 925);
PAINT WHITE (-9775 925);
FORCENOTE
2ND SOURCE:INFENEON BOM
(-9775 700) 0;
DISPLAY LEFT (-9775 700);
DISPLAY 1.021277 (-9775 700);
PAINT WHITE (-9775 700);
FORCENOTE
DCR=0.09M OHM
(-3600 5350) 0;
DISPLAY LEFT (-3600 5350);
DISPLAY 0.638298 (-3600 5350);
PAINT WHITE (-3600 5350);
FORCENOTE
PVDDCR_CPU1_P1_PHASE1
(-7275 5625) 0;
DISPLAY LEFT (-7275 5625);
DISPLAY 1.021277 (-7275 5625);
PAINT WHITE (-7275 5625);
FORCENOTE
6.0*6.1*7.0
(-3600 5400) 0;
DISPLAY LEFT (-3600 5400);
DISPLAY 0.638298 (-3600 5400);
PAINT WHITE (-3600 5400);
FORCENOTE
ISAT:70A@100C
(-3600 5450) 0;
DISPLAY LEFT (-3600 5450);
DISPLAY 0.638298 (-3600 5450);
PAINT WHITE (-3600 5450);
FORCENOTE
PG2292.500HLT
(-3600 5500) 0;
DISPLAY LEFT (-3600 5500);
DISPLAY 0.638298 (-3600 5500);
PAINT WHITE (-3600 5500);
FORCENOTE
DCR=2-3,0.27M OHM
(-2775 1950) 0;
DISPLAY LEFT (-2775 1950);
DISPLAY 0.638298 (-2775 1950);
PAINT WHITE (-2775 1950);
FORCENOTE
PGL6303.151HLT
(-2775 2150) 0;
DISPLAY LEFT (-2775 2150);
DISPLAY 0.638298 (-2775 2150);
PAINT WHITE (-2775 2150);
FORCENOTE
ISAT:70A@100C
(-2775 2100) 0;
DISPLAY LEFT (-2775 2100);
DISPLAY 0.638298 (-2775 2100);
PAINT WHITE (-2775 2100);
FORCENOTE
11.0*7.5*12.5
(-2775 2050) 0;
DISPLAY LEFT (-2775 2050);
DISPLAY 0.638298 (-2775 2050);
PAINT WHITE (-2775 2050);
FORCENOTE
DCR=1-4,0.105M OHM
(-2775 2000) 0;
DISPLAY LEFT (-2775 2000);
DISPLAY 0.638298 (-2775 2000);
PAINT WHITE (-2775 2000);
FORCENOTE
2ND=CV+15^0TZ01
(-2775 1900) 0;
DISPLAY LEFT (-2775 1900);
DISPLAY 0.638298 (-2775 1900);
PAINT WHITE (-2775 1900);
FORCENOTE
3RD=CVA50^0MZ08
(-3600 5250) 0;
DISPLAY LEFT (-3600 5250);
DISPLAY 0.638298 (-3600 5250);
PAINT WHITE (-3600 5250);
FORCENOTE
2ND=CVA50^0MZ07
(-3600 5300) 0;
DISPLAY LEFT (-3600 5300);
DISPLAY 0.638298 (-3600 5300);
PAINT WHITE (-3600 5300);
FORCENOTE
PGL6303.151HLT
(-3175 4775) 0;
DISPLAY LEFT (-3175 4775);
DISPLAY 0.638298 (-3175 4775);
PAINT WHITE (-3175 4775);
FORCENOTE
ISAT:70A@100C
(-3175 4725) 0;
DISPLAY LEFT (-3175 4725);
DISPLAY 0.638298 (-3175 4725);
PAINT WHITE (-3175 4725);
FORCENOTE
11.0*7.5*12.5
(-3175 4675) 0;
DISPLAY LEFT (-3175 4675);
DISPLAY 0.638298 (-3175 4675);
PAINT WHITE (-3175 4675);
FORCENOTE
DCR=1-4,0.105M OHM
(-3175 4625) 0;
DISPLAY LEFT (-3175 4625);
DISPLAY 0.638298 (-3175 4625);
PAINT WHITE (-3175 4625);
FORCENOTE
DCR=2-3,0.27M OHM
(-3175 4575) 0;
DISPLAY LEFT (-3175 4575);
DISPLAY 0.638298 (-3175 4575);
PAINT WHITE (-3175 4575);
FORCENOTE
2ND=CV+15^0TZ01
(-3175 4525) 0;
DISPLAY LEFT (-3175 4525);
DISPLAY 0.638298 (-3175 4525);
PAINT WHITE (-3175 4525);
FORCENOTE
PC374_1,PC373_2,PC404_3,PC403_4,PC422_5,PC135_6 = EMPTY
(-9775 400) 0;
DISPLAY LEFT (-9775 400);
DISPLAY 1.021277 (-9775 400);
PAINT WHITE (-9775 400);
FORCENOTE
PR273,PR268,PR269,PR260,PR261,PR429 = EMPTY
(-9775 475) 0;
DISPLAY LEFT (-9775 475);
DISPLAY 1.021277 (-9775 475);
PAINT WHITE (-9775 475);
FORCENOTE
PR272,PR266,PR267,PR259,PR258,PR428 = CS00002JB38
(-9775 550) 0;
DISPLAY LEFT (-9775 550);
DISPLAY 1.021277 (-9775 550);
PAINT WHITE (-9775 550);
FORCENOTE
PU35,PU5,PU37,PU36,PU38,PU33=AL087000A02/MP87000GMJTH-C06A-Z
(-9800 150) 0;
DISPLAY LEFT (-9800 150);
DISPLAY 1.021277 (-9800 150);
PAINT WHITE (-9800 150);
FORCENOTE
PR260,PR261,PR268,PR269,PR273,PR429=EMPTY
(-9800 0) 0;
DISPLAY LEFT (-9800 0);
DISPLAY 1.021277 (-9800 0);
PAINT WHITE (-9800 0);
FORCENOTE
PR340,PC374_1,PC373_2,PC404_3,PC403_4,PC422_5,PC135_6=EMPTY
(-9800 75) 0;
DISPLAY LEFT (-9800 75);
DISPLAY 1.021277 (-9800 75);
PAINT WHITE (-9800 75);
FORCENOTE
PR341,PR258,PR259,PR266,PR267,PR272,PR428=CS00002JB38
(-9800 -75) 0;
DISPLAY LEFT (-9800 -75);
DISPLAY 1.021277 (-9800 -75);
PAINT WHITE (-9800 -75);
FORCENOTE
3RD SOURCE:MPS BOM
(-9800 225) 0;
DISPLAY LEFT (-9800 225);
DISPLAY 1.021277 (-9800 225);
PAINT WHITE (-9800 225);
FORCENOTE
PR255,PR254,PR263,PR262,PR270,PR426 = CS00002JB38
(-9775 325) 0;
DISPLAY LEFT (-9775 325);
DISPLAY 1.021277 (-9775 325);
PAINT WHITE (-9775 325);
FORCENOTE
2ND=CH722KM8804
(-2250 2300) 0;
DISPLAY LEFT (-2250 2300);
DISPLAY 0.638298 (-2250 2300);
PAINT WHITE (-2250 2300);
FORCENOTE
MAIN=CH122KM8801
(-2250 2350) 0;
DISPLAY LEFT (-2250 2350);
DISPLAY 0.638298 (-2250 2350);
PAINT WHITE (-2250 2350);
FORCENOTE
ESR=4.5M OHM
(-2250 2450) 0;
DISPLAY LEFT (-2250 2450);
DISPLAY 0.638298 (-2250 2450);
PAINT WHITE (-2250 2450);
FORCENOTE
7.3*4.3*1.9
(-2250 2400) 0;
DISPLAY LEFT (-2250 2400);
DISPLAY 0.638298 (-2250 2400);
PAINT WHITE (-2250 2400);
QUIT
